(kicad_sch
	(version 20250114)
	(generator "eeschema")
	(generator_version "9.0")
	(paper "A3")
	(title_block
		(title "Antmicro Baseboard for Jetson AGX Thor")
		(date "2026-02-17")
		(rev "1.1.0")
		(company "Antmicro Ltd")
		(comment 1 "www.antmicro.com")
	)
	(text "7V to 20V\n"
		(exclude_from_sim no)
		(at 193.294 60.452 0)
		(effects
			(font
				(size 1.27 1.27)
			)
		)
	)
	(text "BOOT LED"
		(exclude_from_sim no)
		(at 289.814 206.756 0)
		(effects
			(font
				(size 1.27 1.27)
			)
		)
	)
	(text "Normal case: 10.158ms\nWorst case scenario (R_SET-1%) 10.057ms\nDelay on falling edge only (POL) = 1"
		(exclude_from_sim no)
		(at 147.066 224.536 0)
		(effects
			(font
				(size 1.27 1.27)
			)
			(justify left)
		)
	)
	(text "Simulate button\nclick for autostart"
		(exclude_from_sim no)
		(at 100.965 256.54 0)
		(effects
			(font
				(size 1.27 1.27)
			)
			(justify left bottom)
		)
	)
	(text "Power-up and reset"
		(exclude_from_sim no)
		(at 130.556 140.208 0)
		(effects
			(font
				(size 2.54 2.54)
				(thickness 0.508)
				(bold yes)
			)
		)
	)
	(text "Note: Delay VIN_PWR_ON\nassertion by 5ms\ndeasertion by 2ms\nafter SHDN signal from SOM"
		(exclude_from_sim no)
		(at 96.774 181.102 0)
		(effects
			(font
				(size 1.27 1.27)
			)
			(justify left)
		)
	)
	(text "Reset button"
		(exclude_from_sim no)
		(at 76.2 96.012 0)
		(effects
			(font
				(size 1.27 1.27)
			)
		)
	)
	(text "~{VIN_PWR_BAD} is connected to \nopen-drain SYS_VIN_HV & 5V_{AON} \nDCDC Power-Good signals"
		(exclude_from_sim no)
		(at 26.416 172.72 0)
		(effects
			(font
				(size 1.27 1.27)
			)
			(justify left)
		)
	)
	(text "SoM Power"
		(exclude_from_sim no)
		(at 212.852 22.86 0)
		(effects
			(font
				(size 2.54 2.54)
				(thickness 0.508)
				(bold yes)
			)
			(justify left bottom)
		)
	)
	(text "Discharge circut"
		(exclude_from_sim no)
		(at 330.708 140.208 0)
		(effects
			(font
				(size 2.54 2.54)
				(thickness 0.508)
				(bold yes)
			)
		)
	)
	(text "RC_{const} = 109ms\nEN_{TH}=~55-120ms >= 50ms\nCMOS 5V pin needs \n1.5-3.5V to set HIGH"
		(exclude_from_sim no)
		(at 26.416 184.912 0)
		(effects
			(font
				(size 1.27 1.27)
			)
			(justify left bottom)
		)
	)
	(text "3-2 manual \n1-2 auto\n"
		(exclude_from_sim no)
		(at 54.864 246.126 0)
		(effects
			(font
				(size 1.27 1.27)
			)
		)
	)
	(junction
		(at 179.07 31.75)
		(diameter 0)
		(color 0 0 0 0)
	)
	(junction
		(at 106.68 49.53)
		(diameter 0)
		(color 0 0 0 0)
	)
	(junction
		(at 220.98 39.37)
		(diameter 0)
		(color 0 0 0 0)
	)
	(junction
		(at 363.22 87.63)
		(diameter 0)
		(color 0 0 0 0)
	)
	(junction
		(at 151.13 39.37)
		(diameter 0)
		(color 0 0 0 0)
	)
	(junction
		(at 170.18 31.75)
		(diameter 0)
		(color 0 0 0 0)
	)
	(junction
		(at 128.27 218.44)
		(diameter 0)
		(color 0 0 0 0)
	)
	(junction
		(at 83.82 246.38)
		(diameter 0)
		(color 0 0 0 0)
	)
	(junction
		(at 78.74 101.6)
		(diameter 0)
		(color 0 0 0 0)
	)
	(junction
		(at 33.02 153.67)
		(diameter 0)
		(color 0 0 0 0)
	)
	(junction
		(at 128.27 229.87)
		(diameter 0)
		(color 0 0 0 0)
	)
	(junction
		(at 336.55 232.41)
		(diameter 0)
		(color 0 0 0 0)
	)
	(junction
		(at 204.47 31.75)
		(diameter 0)
		(color 0 0 0 0)
	)
	(junction
		(at 96.52 153.67)
		(diameter 0)
		(color 0 0 0 0)
	)
	(junction
		(at 142.24 41.91)
		(diameter 0)
		(color 0 0 0 0)
	)
	(junction
		(at 196.85 274.32)
		(diameter 0)
		(color 0 0 0 0)
	)
	(junction
		(at 90.17 101.6)
		(diameter 0)
		(color 0 0 0 0)
	)
	(junction
		(at 115.57 31.75)
		(diameter 0)
		(color 0 0 0 0)
	)
	(junction
		(at 195.58 39.37)
		(diameter 0)
		(color 0 0 0 0)
	)
	(junction
		(at 88.9 204.47)
		(diameter 0)
		(color 0 0 0 0)
	)
	(junction
		(at 133.35 31.75)
		(diameter 0)
		(color 0 0 0 0)
	)
	(junction
		(at 375.92 52.07)
		(diameter 0)
		(color 0 0 0 0)
	)
	(junction
		(at 124.46 41.91)
		(diameter 0)
		(color 0 0 0 0)
	)
	(junction
		(at 156.21 190.5)
		(diameter 0)
		(color 0 0 0 0)
	)
	(junction
		(at 82.55 31.75)
		(diameter 0)
		(color 0 0 0 0)
	)
	(junction
		(at 82.55 101.6)
		(diameter 0)
		(color 0 0 0 0)
	)
	(junction
		(at 236.22 241.3)
		(diameter 0)
		(color 0 0 0 0)
	)
	(junction
		(at 142.24 39.37)
		(diameter 0)
		(color 0 0 0 0)
	)
	(junction
		(at 204.47 39.37)
		(diameter 0)
		(color 0 0 0 0)
	)
	(junction
		(at 85.09 101.6)
		(diameter 0)
		(color 0 0 0 0)
	)
	(junction
		(at 375.92 44.45)
		(diameter 0)
		(color 0 0 0 0)
	)
	(junction
		(at 163.83 57.15)
		(diameter 0)
		(color 0 0 0 0)
	)
	(junction
		(at 165.1 243.84)
		(diameter 0)
		(color 0 0 0 0)
	)
	(junction
		(at 229.87 39.37)
		(diameter 0)
		(color 0 0 0 0)
	)
	(junction
		(at 214.63 144.78)
		(diameter 0)
		(color 0 0 0 0)
	)
	(junction
		(at 124.46 39.37)
		(diameter 0)
		(color 0 0 0 0)
	)
	(junction
		(at 187.96 31.75)
		(diameter 0)
		(color 0 0 0 0)
	)
	(junction
		(at 227.33 149.86)
		(diameter 0)
		(color 0 0 0 0)
	)
	(junction
		(at 161.29 246.38)
		(diameter 0)
		(color 0 0 0 0)
	)
	(junction
		(at 128.27 201.93)
		(diameter 0)
		(color 0 0 0 0)
	)
	(junction
		(at 85.09 114.3)
		(diameter 0)
		(color 0 0 0 0)
	)
	(junction
		(at 91.44 175.26)
		(diameter 0)
		(color 0 0 0 0)
	)
	(junction
		(at 142.24 31.75)
		(diameter 0)
		(color 0 0 0 0)
	)
	(junction
		(at 179.07 176.53)
		(diameter 0)
		(color 0 0 0 0)
	)
	(junction
		(at 104.14 201.93)
		(diameter 0)
		(color 0 0 0 0)
	)
	(junction
		(at 363.22 77.47)
		(diameter 0)
		(color 0 0 0 0)
	)
	(junction
		(at 133.35 41.91)
		(diameter 0)
		(color 0 0 0 0)
	)
	(junction
		(at 109.22 201.93)
		(diameter 0)
		(color 0 0 0 0)
	)
	(junction
		(at 148.59 72.39)
		(diameter 0)
		(color 0 0 0 0)
	)
	(junction
		(at 71.12 101.6)
		(diameter 0)
		(color 0 0 0 0)
	)
	(junction
		(at 274.32 189.23)
		(diameter 0)
		(color 0 0 0 0)
	)
	(junction
		(at 182.88 187.96)
		(diameter 0)
		(color 0 0 0 0)
	)
	(junction
		(at 151.13 41.91)
		(diameter 0)
		(color 0 0 0 0)
	)
	(junction
		(at 212.09 142.24)
		(diameter 0)
		(color 0 0 0 0)
	)
	(junction
		(at 185.42 31.75)
		(diameter 0)
		(color 0 0 0 0)
	)
	(junction
		(at 229.87 31.75)
		(diameter 0)
		(color 0 0 0 0)
	)
	(junction
		(at 203.2 274.32)
		(diameter 0)
		(color 0 0 0 0)
	)
	(junction
		(at 212.09 39.37)
		(diameter 0)
		(color 0 0 0 0)
	)
	(junction
		(at 160.02 49.53)
		(diameter 0)
		(color 0 0 0 0)
	)
	(junction
		(at 106.68 39.37)
		(diameter 0)
		(color 0 0 0 0)
	)
	(junction
		(at 160.02 39.37)
		(diameter 0)
		(color 0 0 0 0)
	)
	(junction
		(at 195.58 31.75)
		(diameter 0)
		(color 0 0 0 0)
	)
	(junction
		(at 344.17 240.03)
		(diameter 0)
		(color 0 0 0 0)
	)
	(junction
		(at 133.35 39.37)
		(diameter 0)
		(color 0 0 0 0)
	)
	(junction
		(at 133.35 49.53)
		(diameter 0)
		(color 0 0 0 0)
	)
	(junction
		(at 359.41 77.47)
		(diameter 0)
		(color 0 0 0 0)
	)
	(junction
		(at 236.22 217.17)
		(diameter 0)
		(color 0 0 0 0)
	)
	(junction
		(at 142.24 49.53)
		(diameter 0)
		(color 0 0 0 0)
	)
	(junction
		(at 290.83 177.8)
		(diameter 0)
		(color 0 0 0 0)
	)
	(junction
		(at 95.25 233.68)
		(diameter 0)
		(color 0 0 0 0)
	)
	(junction
		(at 115.57 49.53)
		(diameter 0)
		(color 0 0 0 0)
	)
	(junction
		(at 106.68 31.75)
		(diameter 0)
		(color 0 0 0 0)
	)
	(junction
		(at 124.46 31.75)
		(diameter 0)
		(color 0 0 0 0)
	)
	(junction
		(at 97.79 31.75)
		(diameter 0)
		(color 0 0 0 0)
	)
	(junction
		(at 375.92 59.69)
		(diameter 0)
		(color 0 0 0 0)
	)
	(junction
		(at 154.94 72.39)
		(diameter 0)
		(color 0 0 0 0)
	)
	(junction
		(at 170.18 41.91)
		(diameter 0)
		(color 0 0 0 0)
	)
	(junction
		(at 97.79 175.26)
		(diameter 0)
		(color 0 0 0 0)
	)
	(junction
		(at 97.79 39.37)
		(diameter 0)
		(color 0 0 0 0)
	)
	(junction
		(at 124.46 49.53)
		(diameter 0)
		(color 0 0 0 0)
	)
	(junction
		(at 39.37 31.75)
		(diameter 0)
		(color 0 0 0 0)
	)
	(junction
		(at 359.41 87.63)
		(diameter 0)
		(color 0 0 0 0)
	)
	(junction
		(at 193.04 226.06)
		(diameter 0)
		(color 0 0 0 0)
	)
	(junction
		(at 115.57 39.37)
		(diameter 0)
		(color 0 0 0 0)
	)
	(junction
		(at 236.22 187.96)
		(diameter 0)
		(color 0 0 0 0)
	)
	(junction
		(at 54.61 39.37)
		(diameter 0)
		(color 0 0 0 0)
	)
	(junction
		(at 151.13 49.53)
		(diameter 0)
		(color 0 0 0 0)
	)
	(junction
		(at 218.44 190.5)
		(diameter 0)
		(color 0 0 0 0)
	)
	(junction
		(at 220.98 31.75)
		(diameter 0)
		(color 0 0 0 0)
	)
	(junction
		(at 151.13 31.75)
		(diameter 0)
		(color 0 0 0 0)
	)
	(junction
		(at 160.02 31.75)
		(diameter 0)
		(color 0 0 0 0)
	)
	(junction
		(at 368.3 233.68)
		(diameter 0)
		(color 0 0 0 0)
	)
	(junction
		(at 212.09 31.75)
		(diameter 0)
		(color 0 0 0 0)
	)
	(junction
		(at 356.87 77.47)
		(diameter 0)
		(color 0 0 0 0)
	)
	(junction
		(at 38.1 153.67)
		(diameter 0)
		(color 0 0 0 0)
	)
	(junction
		(at 354.33 233.68)
		(diameter 0)
		(color 0 0 0 0)
	)
	(junction
		(at 115.57 41.91)
		(diameter 0)
		(color 0 0 0 0)
	)
	(junction
		(at 179.07 41.91)
		(diameter 0)
		(color 0 0 0 0)
	)
	(junction
		(at 199.39 238.76)
		(diameter 0)
		(color 0 0 0 0)
	)
	(junction
		(at 298.45 177.8)
		(diameter 0)
		(color 0 0 0 0)
	)
	(junction
		(at 166.37 190.5)
		(diameter 0)
		(color 0 0 0 0)
	)
	(junction
		(at 344.17 220.98)
		(diameter 0)
		(color 0 0 0 0)
	)
	(junction
		(at 160.02 41.91)
		(diameter 0)
		(color 0 0 0 0)
	)
	(junction
		(at 182.88 201.93)
		(diameter 0)
		(color 0 0 0 0)
	)
	(junction
		(at 217.17 147.32)
		(diameter 0)
		(color 0 0 0 0)
	)
	(no_connect
		(at 209.55 153.67)
	)
	(no_connect
		(at 63.5 243.84)
	)
	(no_connect
		(at 194.31 95.25)
	)
	(no_connect
		(at 194.31 97.79)
	)
	(wire
		(pts
			(xy 179.07 175.26) (xy 179.07 176.53)
		)
		(stroke
			(width 0)
			(type default)
		)
	)
	(wire
		(pts
			(xy 104.14 201.93) (xy 109.22 201.93)
		)
		(stroke
			(width 0)
			(type default)
		)
	)
	(wire
		(pts
			(xy 106.68 39.37) (xy 115.57 39.37)
		)
		(stroke
			(width 0)
			(type default)
		)
	)
	(wire
		(pts
			(xy 97.79 39.37) (xy 106.68 39.37)
		)
		(stroke
			(width 0)
			(type default)
		)
	)
	(wire
		(pts
			(xy 323.85 180.34) (xy 323.85 182.88)
		)
		(stroke
			(width 0)
			(type default)
		)
	)
	(wire
		(pts
			(xy 146.05 236.22) (xy 167.64 236.22)
		)
		(stroke
			(width 0)
			(type default)
		)
	)
	(wire
		(pts
			(xy 368.3 87.63) (xy 363.22 87.63)
		)
		(stroke
			(width 0)
			(type default)
		)
	)
	(wire
		(pts
			(xy 91.44 182.88) (xy 91.44 181.61)
		)
		(stroke
			(width 0)
			(type default)
		)
	)
	(wire
		(pts
			(xy 133.35 39.37) (xy 133.35 38.1)
		)
		(stroke
			(width 0)
			(type default)
		)
	)
	(wire
		(pts
			(xy 176.53 88.9) (xy 194.31 88.9)
		)
		(stroke
			(width 0)
			(type default)
		)
	)
	(wire
		(pts
			(xy 290.83 219.71) (xy 290.83 220.98)
		)
		(stroke
			(width 0)
			(type default)
		)
	)
	(wire
		(pts
			(xy 168.91 57.15) (xy 163.83 57.15)
		)
		(stroke
			(width 0)
			(type default)
		)
	)
	(wire
		(pts
			(xy 106.68 31.75) (xy 106.68 33.02)
		)
		(stroke
			(width 0)
			(type default)
		)
	)
	(wire
		(pts
			(xy 168.91 69.85) (xy 168.91 57.15)
		)
		(stroke
			(width 0)
			(type default)
		)
	)
	(wire
		(pts
			(xy 182.88 176.53) (xy 182.88 187.96)
		)
		(stroke
			(width 0)
			(type default)
		)
	)
	(wire
		(pts
			(xy 95.25 240.03) (xy 95.25 241.3)
		)
		(stroke
			(width 0)
			(type default)
		)
	)
	(wire
		(pts
			(xy 251.46 76.2) (xy 269.24 76.2)
		)
		(stroke
			(width 0)
			(type default)
		)
	)
	(wire
		(pts
			(xy 128.27 229.87) (xy 128.27 236.22)
		)
		(stroke
			(width 0)
			(type default)
		)
	)
	(wire
		(pts
			(xy 160.02 33.02) (xy 160.02 31.75)
		)
		(stroke
			(width 0)
			(type default)
		)
	)
	(wire
		(pts
			(xy 115.57 39.37) (xy 124.46 39.37)
		)
		(stroke
			(width 0)
			(type default)
		)
	)
	(wire
		(pts
			(xy 95.25 232.41) (xy 95.25 233.68)
		)
		(stroke
			(width 0)
			(type default)
		)
	)
	(wire
		(pts
			(xy 165.1 241.3) (xy 165.1 243.84)
		)
		(stroke
			(width 0)
			(type default)
		)
	)
	(wire
		(pts
			(xy 161.29 238.76) (xy 167.64 238.76)
		)
		(stroke
			(width 0)
			(type default)
		)
	)
	(wire
		(pts
			(xy 229.87 39.37) (xy 229.87 40.64)
		)
		(stroke
			(width 0)
			(type default)
		)
	)
	(wire
		(pts
			(xy 91.44 175.26) (xy 91.44 176.53)
		)
		(stroke
			(width 0)
			(type default)
		)
	)
	(wire
		(pts
			(xy 195.58 31.75) (xy 204.47 31.75)
		)
		(stroke
			(width 0)
			(type default)
		)
	)
	(wire
		(pts
			(xy 38.1 153.67) (xy 38.1 152.4)
		)
		(stroke
			(width 0)
			(type default)
		)
	)
	(wire
		(pts
			(xy 229.87 38.1) (xy 229.87 39.37)
		)
		(stroke
			(width 0)
			(type default)
		)
	)
	(wire
		(pts
			(xy 97.79 39.37) (xy 97.79 40.64)
		)
		(stroke
			(width 0)
			(type default)
		)
	)
	(wire
		(pts
			(xy 85.09 113.03) (xy 85.09 114.3)
		)
		(stroke
			(width 0)
			(type default)
		)
	)
	(wire
		(pts
			(xy 58.42 248.92) (xy 63.5 248.92)
		)
		(stroke
			(width 0)
			(type default)
		)
	)
	(wire
		(pts
			(xy 151.13 33.02) (xy 151.13 31.75)
		)
		(stroke
			(width 0)
			(type default)
		)
	)
	(wire
		(pts
			(xy 218.44 190.5) (xy 234.95 190.5)
		)
		(stroke
			(width 0)
			(type default)
		)
	)
	(wire
		(pts
			(xy 160.02 49.53) (xy 160.02 48.26)
		)
		(stroke
			(width 0)
			(type default)
		)
	)
	(wire
		(pts
			(xy 104.14 101.6) (xy 90.17 101.6)
		)
		(stroke
			(width 0)
			(type default)
		)
	)
	(wire
		(pts
			(xy 194.31 78.74) (xy 194.31 80.01)
		)
		(stroke
			(width 0)
			(type default)
		)
	)
	(polyline
		(pts
			(xy 12.065 129.54) (xy 408.305 129.54)
		)
		(stroke
			(width 0)
			(type default)
		)
	)
	(wire
		(pts
			(xy 161.29 240.03) (xy 161.29 238.76)
		)
		(stroke
			(width 0)
			(type default)
		)
	)
	(wire
		(pts
			(xy 39.37 30.48) (xy 39.37 31.75)
		)
		(stroke
			(width 0)
			(type default)
		)
	)
	(wire
		(pts
			(xy 160.02 41.91) (xy 170.18 41.91)
		)
		(stroke
			(width 0)
			(type default)
		)
	)
	(wire
		(pts
			(xy 220.98 241.3) (xy 227.33 241.3)
		)
		(stroke
			(width 0)
			(type default)
		)
	)
	(wire
		(pts
			(xy 220.98 217.17) (xy 226.06 217.17)
		)
		(stroke
			(width 0)
			(type default)
		)
	)
	(wire
		(pts
			(xy 383.54 223.52) (xy 383.54 233.68)
		)
		(stroke
			(width 0)
			(type default)
		)
	)
	(wire
		(pts
			(xy 201.93 152.4) (xy 201.93 154.94)
		)
		(stroke
			(width 0)
			(type default)
		)
	)
	(wire
		(pts
			(xy 128.27 200.66) (xy 128.27 201.93)
		)
		(stroke
			(width 0)
			(type default)
		)
	)
	(wire
		(pts
			(xy 91.44 168.91) (xy 91.44 157.48)
		)
		(stroke
			(width 0)
			(type default)
		)
	)
	(wire
		(pts
			(xy 215.9 278.13) (xy 215.9 276.86)
		)
		(stroke
			(width 0)
			(type default)
		)
	)
	(wire
		(pts
			(xy 106.68 50.8) (xy 106.68 49.53)
		)
		(stroke
			(width 0)
			(type default)
		)
	)
	(wire
		(pts
			(xy 290.83 191.77) (xy 290.83 199.39)
		)
		(stroke
			(width 0)
			(type default)
		)
	)
	(wire
		(pts
			(xy 375.92 59.69) (xy 378.46 59.69)
		)
		(stroke
			(width 0)
			(type default)
		)
	)
	(wire
		(pts
			(xy 344.17 217.17) (xy 344.17 220.98)
		)
		(stroke
			(width 0)
			(type default)
		)
	)
	(wire
		(pts
			(xy 187.96 31.75) (xy 187.96 33.02)
		)
		(stroke
			(width 0)
			(type default)
		)
	)
	(wire
		(pts
			(xy 350.52 220.98) (xy 350.52 233.68)
		)
		(stroke
			(width 0)
			(type default)
		)
	)
	(wire
		(pts
			(xy 205.74 193.04) (xy 207.01 193.04)
		)
		(stroke
			(width 0)
			(type default)
		)
	)
	(wire
		(pts
			(xy 82.55 114.3) (xy 85.09 114.3)
		)
		(stroke
			(width 0)
			(type default)
		)
	)
	(wire
		(pts
			(xy 160.02 39.37) (xy 170.18 39.37)
		)
		(stroke
			(width 0)
			(type default)
		)
	)
	(wire
		(pts
			(xy 132.08 72.39) (xy 132.08 69.85)
		)
		(stroke
			(width 0)
			(type default)
		)
	)
	(wire
		(pts
			(xy 236.22 217.17) (xy 236.22 241.3)
		)
		(stroke
			(width 0)
			(type default)
		)
	)
	(wire
		(pts
			(xy 229.87 31.75) (xy 229.87 33.02)
		)
		(stroke
			(width 0)
			(type default)
		)
	)
	(wire
		(pts
			(xy 368.3 223.52) (xy 368.3 233.68)
		)
		(stroke
			(width 0)
			(type default)
		)
	)
	(wire
		(pts
			(xy 151.13 49.53) (xy 151.13 48.26)
		)
		(stroke
			(width 0)
			(type default)
		)
	)
	(wire
		(pts
			(xy 368.3 223.52) (xy 369.57 223.52)
		)
		(stroke
			(width 0)
			(type default)
		)
	)
	(wire
		(pts
			(xy 214.63 144.78) (xy 228.6 144.78)
		)
		(stroke
			(width 0)
			(type default)
		)
	)
	(wire
		(pts
			(xy 199.39 237.49) (xy 199.39 238.76)
		)
		(stroke
			(width 0)
			(type default)
		)
	)
	(wire
		(pts
			(xy 203.2 274.32) (xy 209.55 274.32)
		)
		(stroke
			(width 0)
			(type default)
		)
	)
	(wire
		(pts
			(xy 205.74 190.5) (xy 209.55 190.5)
		)
		(stroke
			(width 0)
			(type default)
		)
	)
	(wire
		(pts
			(xy 151.13 31.75) (xy 160.02 31.75)
		)
		(stroke
			(width 0)
			(type default)
		)
	)
	(wire
		(pts
			(xy 298.45 177.8) (xy 298.45 187.96)
		)
		(stroke
			(width 0)
			(type default)
		)
	)
	(wire
		(pts
			(xy 336.55 240.03) (xy 336.55 238.76)
		)
		(stroke
			(width 0)
			(type default)
		)
	)
	(wire
		(pts
			(xy 97.79 38.1) (xy 97.79 39.37)
		)
		(stroke
			(width 0)
			(type default)
		)
	)
	(wire
		(pts
			(xy 204.47 31.75) (xy 212.09 31.75)
		)
		(stroke
			(width 0)
			(type default)
		)
	)
	(wire
		(pts
			(xy 273.05 189.23) (xy 274.32 189.23)
		)
		(stroke
			(width 0)
			(type default)
		)
	)
	(wire
		(pts
			(xy 96.52 149.86) (xy 96.52 153.67)
		)
		(stroke
			(width 0)
			(type default)
		)
	)
	(wire
		(pts
			(xy 199.39 226.06) (xy 199.39 232.41)
		)
		(stroke
			(width 0)
			(type default)
		)
	)
	(wire
		(pts
			(xy 236.22 179.07) (xy 236.22 177.8)
		)
		(stroke
			(width 0)
			(type default)
		)
	)
	(wire
		(pts
			(xy 161.29 245.11) (xy 161.29 246.38)
		)
		(stroke
			(width 0)
			(type default)
		)
	)
	(wire
		(pts
			(xy 356.87 77.47) (xy 359.41 77.47)
		)
		(stroke
			(width 0)
			(type default)
		)
	)
	(wire
		(pts
			(xy 363.22 77.47) (xy 368.3 77.47)
		)
		(stroke
			(width 0)
			(type default)
		)
	)
	(wire
		(pts
			(xy 133.35 33.02) (xy 133.35 31.75)
		)
		(stroke
			(width 0)
			(type default)
		)
	)
	(wire
		(pts
			(xy 220.98 39.37) (xy 229.87 39.37)
		)
		(stroke
			(width 0)
			(type default)
		)
	)
	(wire
		(pts
			(xy 106.68 49.53) (xy 115.57 49.53)
		)
		(stroke
			(width 0)
			(type default)
		)
	)
	(wire
		(pts
			(xy 78.74 110.49) (xy 78.74 115.57)
		)
		(stroke
			(width 0)
			(type default)
		)
	)
	(wire
		(pts
			(xy 97.79 31.75) (xy 97.79 33.02)
		)
		(stroke
			(width 0)
			(type default)
		)
	)
	(wire
		(pts
			(xy 232.41 241.3) (xy 236.22 241.3)
		)
		(stroke
			(width 0)
			(type default)
		)
	)
	(wire
		(pts
			(xy 368.3 233.68) (xy 383.54 233.68)
		)
		(stroke
			(width 0)
			(type default)
		)
	)
	(wire
		(pts
			(xy 199.39 238.76) (xy 199.39 242.57)
		)
		(stroke
			(width 0)
			(type default)
		)
	)
	(wire
		(pts
			(xy 38.1 153.67) (xy 64.77 153.67)
		)
		(stroke
			(width 0)
			(type default)
		)
	)
	(wire
		(pts
			(xy 95.25 233.68) (xy 95.25 234.95)
		)
		(stroke
			(width 0)
			(type default)
		)
	)
	(wire
		(pts
			(xy 194.31 147.32) (xy 217.17 147.32)
		)
		(stroke
			(width 0)
			(type default)
		)
	)
	(wire
		(pts
			(xy 54.61 104.14) (xy 54.61 106.68)
		)
		(stroke
			(width 0)
			(type default)
		)
	)
	(wire
		(pts
			(xy 120.65 248.92) (xy 120.65 259.08)
		)
		(stroke
			(width 0)
			(type default)
		)
	)
	(wire
		(pts
			(xy 83.82 160.02) (xy 85.09 160.02)
		)
		(stroke
			(width 0)
			(type default)
		)
	)
	(wire
		(pts
			(xy 204.47 31.75) (xy 204.47 33.02)
		)
		(stroke
			(width 0)
			(type default)
		)
	)
	(wire
		(pts
			(xy 118.11 229.87) (xy 118.11 227.33)
		)
		(stroke
			(width 0)
			(type default)
		)
	)
	(wire
		(pts
			(xy 350.52 233.68) (xy 354.33 233.68)
		)
		(stroke
			(width 0)
			(type default)
		)
	)
	(wire
		(pts
			(xy 217.17 147.32) (xy 228.6 147.32)
		)
		(stroke
			(width 0)
			(type default)
		)
	)
	(wire
		(pts
			(xy 38.1 153.67) (xy 38.1 154.94)
		)
		(stroke
			(width 0)
			(type default)
		)
	)
	(wire
		(pts
			(xy 212.09 39.37) (xy 220.98 39.37)
		)
		(stroke
			(width 0)
			(type default)
		)
	)
	(wire
		(pts
			(xy 204.47 38.1) (xy 204.47 39.37)
		)
		(stroke
			(width 0)
			(type default)
		)
	)
	(wire
		(pts
			(xy 227.33 149.86) (xy 228.6 149.86)
		)
		(stroke
			(width 0)
			(type default)
		)
	)
	(wire
		(pts
			(xy 148.59 88.9) (xy 148.59 91.44)
		)
		(stroke
			(width 0)
			(type default)
		)
	)
	(wire
		(pts
			(xy 90.17 101.6) (xy 90.17 100.33)
		)
		(stroke
			(width 0)
			(type default)
		)
	)
	(wire
		(pts
			(xy 91.44 175.26) (xy 91.44 173.99)
		)
		(stroke
			(width 0)
			(type default)
		)
	)
	(wire
		(pts
			(xy 106.68 31.75) (xy 97.79 31.75)
		)
		(stroke
			(width 0)
			(type default)
		)
	)
	(wire
		(pts
			(xy 220.98 31.75) (xy 229.87 31.75)
		)
		(stroke
			(width 0)
			(type default)
		)
	)
	(wire
		(pts
			(xy 39.37 38.1) (xy 39.37 39.37)
		)
		(stroke
			(width 0)
			(type default)
		)
	)
	(wire
		(pts
			(xy 236.22 187.96) (xy 238.76 187.96)
		)
		(stroke
			(width 0)
			(type default)
		)
	)
	(wire
		(pts
			(xy 375.92 59.69) (xy 375.92 62.23)
		)
		(stroke
			(width 0)
			(type default)
		)
	)
	(wire
		(pts
			(xy 368.3 85.09) (xy 368.3 87.63)
		)
		(stroke
			(width 0)
			(type default)
		)
	)
	(wire
		(pts
			(xy 194.31 142.24) (xy 212.09 142.24)
		)
		(stroke
			(width 0)
			(type default)
		)
	)
	(wire
		(pts
			(xy 133.35 41.91) (xy 142.24 41.91)
		)
		(stroke
			(width 0)
			(type default)
		)
	)
	(wire
		(pts
			(xy 133.35 41.91) (xy 133.35 43.18)
		)
		(stroke
			(width 0)
			(type default)
		)
	)
	(wire
		(pts
			(xy 104.14 204.47) (xy 104.14 201.93)
		)
		(stroke
			(width 0)
			(type default)
		)
	)
	(wire
		(pts
			(xy 64.77 151.13) (xy 60.96 151.13)
		)
		(stroke
			(width 0)
			(type default)
		)
	)
	(wire
		(pts
			(xy 207.01 193.04) (xy 207.01 194.31)
		)
		(stroke
			(width 0)
			(type default)
		)
	)
	(wire
		(pts
			(xy 99.06 243.84) (xy 99.06 233.68)
		)
		(stroke
			(width 0)
			(type default)
		)
	)
	(wire
		(pts
			(xy 307.34 156.21) (xy 307.34 157.48)
		)
		(stroke
			(width 0)
			(type default)
		)
	)
	(wire
		(pts
			(xy 298.45 177.8) (xy 300.99 177.8)
		)
		(stroke
			(width 0)
			(type default)
		)
	)
	(wire
		(pts
			(xy 106.68 38.1) (xy 106.68 39.37)
		)
		(stroke
			(width 0)
			(type default)
		)
	)
	(wire
		(pts
			(xy 148.59 78.74) (xy 148.59 80.01)
		)
		(stroke
			(width 0)
			(type default)
		)
	)
	(wire
		(pts
			(xy 97.79 175.26) (xy 97.79 173.99)
		)
		(stroke
			(width 0)
			(type default)
		)
	)
	(wire
		(pts
			(xy 344.17 240.03) (xy 344.17 242.57)
		)
		(stroke
			(width 0)
			(type default)
		)
	)
	(wire
		(pts
			(xy 82.55 102.87) (xy 82.55 101.6)
		)
		(stroke
			(width 0)
			(type default)
		)
	)
	(wire
		(pts
			(xy 96.52 143.51) (xy 96.52 144.78)
		)
		(stroke
			(width 0)
			(type default)
		)
	)
	(wire
		(pts
			(xy 166.37 190.5) (xy 187.96 190.5)
		)
		(stroke
			(width 0)
			(type default)
		)
	)
	(wire
		(pts
			(xy 148.59 68.58) (xy 148.59 72.39)
		)
		(stroke
			(width 0)
			(type default)
		)
	)
	(wire
		(pts
			(xy 91.44 175.26) (xy 97.79 175.26)
		)
		(stroke
			(width 0)
			(type default)
		)
	)
	(wire
		(pts
			(xy 142.24 31.75) (xy 151.13 31.75)
		)
		(stroke
			(width 0)
			(type default)
		)
	)
	(wire
		(pts
			(xy 82.55 40.64) (xy 82.55 41.91)
		)
		(stroke
			(width 0)
			(type default)
		)
	)
	(wire
		(pts
			(xy 124.46 39.37) (xy 124.46 38.1)
		)
		(stroke
			(width 0)
			(type default)
		)
	)
	(wire
		(pts
			(xy 99.06 243.84) (xy 100.33 243.84)
		)
		(stroke
			(width 0)
			(type default)
		)
	)
	(wire
		(pts
			(xy 274.32 189.23) (xy 284.48 189.23)
		)
		(stroke
			(width 0)
			(type default)
		)
	)
	(wire
		(pts
			(xy 236.22 241.3) (xy 240.03 241.3)
		)
		(stroke
			(width 0)
			(type default)
		)
	)
	(wire
		(pts
			(xy 229.87 31.75) (xy 265.43 31.75)
		)
		(stroke
			(width 0)
			(type default)
		)
	)
	(wire
		(pts
			(xy 151.13 39.37) (xy 160.02 39.37)
		)
		(stroke
			(width 0)
			(type default)
		)
	)
	(wire
		(pts
			(xy 187.96 38.1) (xy 187.96 39.37)
		)
		(stroke
			(width 0)
			(type default)
		)
	)
	(wire
		(pts
			(xy 323.85 162.56) (xy 323.85 170.18)
		)
		(stroke
			(width 0)
			(type default)
		)
	)
	(wire
		(pts
			(xy 78.74 101.6) (xy 78.74 105.41)
		)
		(stroke
			(width 0)
			(type default)
		)
	)
	(wire
		(pts
			(xy 170.18 33.02) (xy 170.18 31.75)
		)
		(stroke
			(width 0)
			(type default)
		)
	)
	(wire
		(pts
			(xy 212.09 153.67) (xy 212.09 142.24)
		)
		(stroke
			(width 0)
			(type default)
		)
	)
	(wire
		(pts
			(xy 71.12 101.6) (xy 60.96 101.6)
		)
		(stroke
			(width 0)
			(type default)
		)
	)
	(wire
		(pts
			(xy 120.65 248.92) (xy 118.11 248.92)
		)
		(stroke
			(width 0)
			(type default)
		)
	)
	(wire
		(pts
			(xy 185.42 236.22) (xy 185.42 226.06)
		)
		(stroke
			(width 0)
			(type default)
		)
	)
	(wire
		(pts
			(xy 142.24 41.91) (xy 151.13 41.91)
		)
		(stroke
			(width 0)
			(type default)
		)
	)
	(wire
		(pts
			(xy 109.22 209.55) (xy 109.22 210.82)
		)
		(stroke
			(width 0)
			(type default)
		)
	)
	(wire
		(pts
			(xy 161.29 246.38) (xy 161.29 248.92)
		)
		(stroke
			(width 0)
			(type default)
		)
	)
	(wire
		(pts
			(xy 160.02 31.75) (xy 170.18 31.75)
		)
		(stroke
			(width 0)
			(type default)
		)
	)
	(wire
		(pts
			(xy 148.59 72.39) (xy 154.94 72.39)
		)
		(stroke
			(width 0)
			(type default)
		)
	)
	(wire
		(pts
			(xy 179.07 176.53) (xy 179.07 177.8)
		)
		(stroke
			(width 0)
			(type default)
		)
	)
	(wire
		(pts
			(xy 251.46 73.66) (xy 269.24 73.66)
		)
		(stroke
			(width 0)
			(type default)
		)
	)
	(wire
		(pts
			(xy 307.34 180.34) (xy 307.34 182.88)
		)
		(stroke
			(width 0)
			(type default)
		)
	)
	(wire
		(pts
			(xy 207.01 152.4) (xy 207.01 153.67)
		)
		(stroke
			(width 0)
			(type default)
		)
	)
	(wire
		(pts
			(xy 124.46 41.91) (xy 124.46 43.18)
		)
		(stroke
			(width 0)
			(type default)
		)
	)
	(wire
		(pts
			(xy 298.45 187.96) (xy 317.5 187.96)
		)
		(stroke
			(width 0)
			(type default)
		)
	)
	(wire
		(pts
			(xy 39.37 39.37) (xy 54.61 39.37)
		)
		(stroke
			(width 0)
			(type default)
		)
	)
	(wire
		(pts
			(xy 359.41 77.47) (xy 363.22 77.47)
		)
		(stroke
			(width 0)
			(type default)
		)
	)
	(wire
		(pts
			(xy 363.22 87.63) (xy 359.41 87.63)
		)
		(stroke
			(width 0)
			(type default)
		)
	)
	(wire
		(pts
			(xy 363.22 87.63) (xy 363.22 88.9)
		)
		(stroke
			(width 0)
			(type default)
		)
	)
	(wire
		(pts
			(xy 251.46 93.98) (xy 276.86 93.98)
		)
		(stroke
			(width 0)
			(type default)
		)
	)
	(wire
		(pts
			(xy 160.02 49.53) (xy 170.18 49.53)
		)
		(stroke
			(width 0)
			(type default)
		)
	)
	(wire
		(pts
			(xy 109.22 201.93) (xy 128.27 201.93)
		)
		(stroke
			(width 0)
			(type default)
		)
	)
	(wire
		(pts
			(xy 375.92 44.45) (xy 375.92 52.07)
		)
		(stroke
			(width 0)
			(type default)
		)
	)
	(wire
		(pts
			(xy 133.35 49.53) (xy 133.35 48.26)
		)
		(stroke
			(width 0)
			(type default)
		)
	)
	(wire
		(pts
			(xy 307.34 162.56) (xy 307.34 170.18)
		)
		(stroke
			(width 0)
			(type default)
		)
	)
	(wire
		(pts
			(xy 88.9 201.93) (xy 91.44 201.93)
		)
		(stroke
			(width 0)
			(type default)
		)
	)
	(wire
		(pts
			(xy 128.27 218.44) (xy 128.27 222.25)
		)
		(stroke
			(width 0)
			(type default)
		)
	)
	(wire
		(pts
			(xy 142.24 39.37) (xy 142.24 38.1)
		)
		(stroke
			(width 0)
			(type default)
		)
	)
	(wire
		(pts
			(xy 218.44 193.04) (xy 218.44 190.5)
		)
		(stroke
			(width 0)
			(type default)
		)
	)
	(wire
		(pts
			(xy 54.61 39.37) (xy 54.61 40.64)
		)
		(stroke
			(width 0)
			(type default)
		)
	)
	(wire
		(pts
			(xy 167.64 241.3) (xy 165.1 241.3)
		)
		(stroke
			(width 0)
			(type default)
		)
	)
	(wire
		(pts
			(xy 58.42 251.46) (xy 58.42 248.92)
		)
		(stroke
			(width 0)
			(type default)
		)
	)
	(wire
		(pts
			(xy 71.12 110.49) (xy 71.12 115.57)
		)
		(stroke
			(width 0)
			(type default)
		)
	)
	(wire
		(pts
			(xy 344.17 220.98) (xy 350.52 220.98)
		)
		(stroke
			(width 0)
			(type default)
		)
	)
	(wire
		(pts
			(xy 204.47 39.37) (xy 212.09 39.37)
		)
		(stroke
			(width 0)
			(type default)
		)
	)
	(wire
		(pts
			(xy 160.02 39.37) (xy 160.02 38.1)
		)
		(stroke
			(width 0)
			(type default)
		)
	)
	(wire
		(pts
			(xy 91.44 157.48) (xy 83.82 157.48)
		)
		(stroke
			(width 0)
			(type default)
		)
	)
	(wire
		(pts
			(xy 193.04 78.74) (xy 194.31 78.74)
		)
		(stroke
			(width 0)
			(type default)
		)
	)
	(wire
		(pts
			(xy 196.85 273.05) (xy 196.85 274.32)
		)
		(stroke
			(width 0)
			(type default)
		)
	)
	(wire
		(pts
			(xy 196.85 274.32) (xy 203.2 274.32)
		)
		(stroke
			(width 0)
			(type default)
		)
	)
	(wire
		(pts
			(xy 290.83 226.06) (xy 290.83 227.33)
		)
		(stroke
			(width 0)
			(type default)
		)
	)
	(wire
		(pts
			(xy 82.55 101.6) (xy 78.74 101.6)
		)
		(stroke
			(width 0)
			(type default)
		)
	)
	(wire
		(pts
			(xy 115.57 38.1) (xy 115.57 39.37)
		)
		(stroke
			(width 0)
			(type default)
		)
	)
	(wire
		(pts
			(xy 336.55 232.41) (xy 337.82 232.41)
		)
		(stroke
			(width 0)
			(type default)
		)
	)
	(wire
		(pts
			(xy 344.17 234.95) (xy 344.17 240.03)
		)
		(stroke
			(width 0)
			(type default)
		)
	)
	(wire
		(pts
			(xy 165.1 246.38) (xy 161.29 246.38)
		)
		(stroke
			(width 0)
			(type default)
		)
	)
	(wire
		(pts
			(xy 176.53 85.09) (xy 194.31 85.09)
		)
		(stroke
			(width 0)
			(type default)
		)
	)
	(wire
		(pts
			(xy 265.43 30.48) (xy 265.43 31.75)
		)
		(stroke
			(width 0)
			(type default)
		)
	)
	(wire
		(pts
			(xy 39.37 33.02) (xy 39.37 31.75)
		)
		(stroke
			(width 0)
			(type default)
		)
	)
	(wire
		(pts
			(xy 165.1 243.84) (xy 167.64 243.84)
		)
		(stroke
			(width 0)
			(type default)
		)
	)
	(wire
		(pts
			(xy 166.37 180.34) (xy 166.37 182.88)
		)
		(stroke
			(width 0)
			(type default)
		)
	)
	(wire
		(pts
			(xy 189.23 91.44) (xy 189.23 92.71)
		)
		(stroke
			(width 0)
			(type default)
		)
	)
	(wire
		(pts
			(xy 133.35 31.75) (xy 142.24 31.75)
		)
		(stroke
			(width 0)
			(type default)
		)
	)
	(wire
		(pts
			(xy 54.61 92.71) (xy 54.61 93.98)
		)
		(stroke
			(width 0)
			(type default)
		)
	)
	(polyline
		(pts
			(xy 257.81 129.54) (xy 257.81 285.115)
		)
		(stroke
			(width 0)
			(type default)
		)
	)
	(wire
		(pts
			(xy 170.18 39.37) (xy 170.18 38.1)
		)
		(stroke
			(width 0)
			(type default)
		)
	)
	(wire
		(pts
			(xy 194.31 144.78) (xy 214.63 144.78)
		)
		(stroke
			(width 0)
			(type default)
		)
	)
	(wire
		(pts
			(xy 185.42 31.75) (xy 187.96 31.75)
		)
		(stroke
			(width 0)
			(type default)
		)
	)
	(wire
		(pts
			(xy 85.09 102.87) (xy 85.09 101.6)
		)
		(stroke
			(width 0)
			(type default)
		)
	)
	(wire
		(pts
			(xy 151.13 41.91) (xy 151.13 43.18)
		)
		(stroke
			(width 0)
			(type default)
		)
	)
	(wire
		(pts
			(xy 124.46 49.53) (xy 124.46 48.26)
		)
		(stroke
			(width 0)
			(type default)
		)
	)
	(wire
		(pts
			(xy 115.57 31.75) (xy 115.57 33.02)
		)
		(stroke
			(width 0)
			(type default)
		)
	)
	(wire
		(pts
			(xy 60.96 144.78) (xy 60.96 151.13)
		)
		(stroke
			(width 0)
			(type default)
		)
	)
	(wire
		(pts
			(xy 220.98 38.1) (xy 220.98 39.37)
		)
		(stroke
			(width 0)
			(type default)
		)
	)
	(wire
		(pts
			(xy 83.82 245.11) (xy 83.82 246.38)
		)
		(stroke
			(width 0)
			(type default)
		)
	)
	(wire
		(pts
			(xy 375.92 226.06) (xy 375.92 228.6)
		)
		(stroke
			(width 0)
			(type default)
		)
	)
	(wire
		(pts
			(xy 187.96 31.75) (xy 195.58 31.75)
		)
		(stroke
			(width 0)
			(type default)
		)
	)
	(wire
		(pts
			(xy 185.42 64.77) (xy 194.31 64.77)
		)
		(stroke
			(width 0)
			(type default)
		)
	)
	(wire
		(pts
			(xy 92.71 248.92) (xy 100.33 248.92)
		)
		(stroke
			(width 0)
			(type default)
		)
	)
	(wire
		(pts
			(xy 62.23 31.75) (xy 71.12 31.75)
		)
		(stroke
			(width 0)
			(type default)
		)
	)
	(wire
		(pts
			(xy 193.04 115.57) (xy 194.31 115.57)
		)
		(stroke
			(width 0)
			(type default)
		)
	)
	(wire
		(pts
			(xy 354.33 233.68) (xy 368.3 233.68)
		)
		(stroke
			(width 0)
			(type default)
		)
	)
	(wire
		(pts
			(xy 148.59 72.39) (xy 148.59 73.66)
		)
		(stroke
			(width 0)
			(type default)
		)
	)
	(wire
		(pts
			(xy 217.17 153.67) (xy 217.17 147.32)
		)
		(stroke
			(width 0)
			(type default)
		)
	)
	(wire
		(pts
			(xy 375.92 201.93) (xy 375.92 203.2)
		)
		(stroke
			(width 0)
			(type default)
		)
	)
	(wire
		(pts
			(xy 212.09 38.1) (xy 212.09 39.37)
		)
		(stroke
			(width 0)
			(type default)
		)
	)
	(wire
		(pts
			(xy 96.52 153.67) (xy 120.65 153.67)
		)
		(stroke
			(width 0)
			(type default)
		)
	)
	(wire
		(pts
			(xy 115.57 41.91) (xy 115.57 43.18)
		)
		(stroke
			(width 0)
			(type default)
		)
	)
	(wire
		(pts
			(xy 195.58 38.1) (xy 195.58 39.37)
		)
		(stroke
			(width 0)
			(type default)
		)
	)
	(wire
		(pts
			(xy 170.18 41.91) (xy 179.07 41.91)
		)
		(stroke
			(width 0)
			(type default)
		)
	)
	(wire
		(pts
			(xy 195.58 31.75) (xy 195.58 33.02)
		)
		(stroke
			(width 0)
			(type default)
		)
	)
	(wire
		(pts
			(xy 170.18 49.53) (xy 170.18 48.26)
		)
		(stroke
			(width 0)
			(type default)
		)
	)
	(wire
		(pts
			(xy 212.09 142.24) (xy 228.6 142.24)
		)
		(stroke
			(width 0)
			(type default)
		)
	)
	(wire
		(pts
			(xy 118.11 218.44) (xy 128.27 218.44)
		)
		(stroke
			(width 0)
			(type default)
		)
	)
	(wire
		(pts
			(xy 176.53 82.55) (xy 194.31 82.55)
		)
		(stroke
			(width 0)
			(type default)
		)
	)
	(wire
		(pts
			(xy 115.57 49.53) (xy 124.46 49.53)
		)
		(stroke
			(width 0)
			(type default)
		)
	)
	(wire
		(pts
			(xy 92.71 248.92) (xy 92.71 251.46)
		)
		(stroke
			(width 0)
			(type default)
		)
	)
	(wire
		(pts
			(xy 34.29 48.26) (xy 48.26 48.26)
		)
		(stroke
			(width 0)
			(type default)
		)
	)
	(wire
		(pts
			(xy 76.2 248.92) (xy 76.2 251.46)
		)
		(stroke
			(width 0)
			(type default)
		)
	)
	(wire
		(pts
			(xy 193.04 226.06) (xy 199.39 226.06)
		)
		(stroke
			(width 0)
			(type default)
		)
	)
	(wire
		(pts
			(xy 215.9 266.7) (xy 226.06 266.7)
		)
		(stroke
			(width 0)
			(type default)
		)
	)
	(wire
		(pts
			(xy 54.61 50.8) (xy 54.61 52.07)
		)
		(stroke
			(width 0)
			(type default)
		)
	)
	(wire
		(pts
			(xy 97.79 168.91) (xy 97.79 167.64)
		)
		(stroke
			(width 0)
			(type default)
		)
	)
	(wire
		(pts
			(xy 359.41 87.63) (xy 356.87 87.63)
		)
		(stroke
			(width 0)
			(type default)
		)
	)
	(wire
		(pts
			(xy 156.21 187.96) (xy 156.21 190.5)
		)
		(stroke
			(width 0)
			(type default)
		)
	)
	(wire
		(pts
			(xy 212.09 31.75) (xy 212.09 33.02)
		)
		(stroke
			(width 0)
			(type default)
		)
	)
	(wire
		(pts
			(xy 391.16 201.93) (xy 391.16 203.2)
		)
		(stroke
			(width 0)
			(type default)
		)
	)
	(wire
		(pts
			(xy 118.11 222.25) (xy 118.11 218.44)
		)
		(stroke
			(width 0)
			(type default)
		)
	)
	(wire
		(pts
			(xy 54.61 38.1) (xy 54.61 39.37)
		)
		(stroke
			(width 0)
			(type default)
		)
	)
	(wire
		(pts
			(xy 251.46 78.74) (xy 262.89 78.74)
		)
		(stroke
			(width 0)
			(type default)
		)
	)
	(wire
		(pts
			(xy 336.55 240.03) (xy 344.17 240.03)
		)
		(stroke
			(width 0)
			(type default)
		)
	)
	(wire
		(pts
			(xy 85.09 101.6) (xy 82.55 101.6)
		)
		(stroke
			(width 0)
			(type default)
		)
	)
	(wire
		(pts
			(xy 182.88 187.96) (xy 187.96 187.96)
		)
		(stroke
			(width 0)
			(type default)
		)
	)
	(wire
		(pts
			(xy 142.24 49.53) (xy 142.24 48.26)
		)
		(stroke
			(width 0)
			(type default)
		)
	)
	(wire
		(pts
			(xy 327.66 232.41) (xy 336.55 232.41)
		)
		(stroke
			(width 0)
			(type default)
		)
	)
	(wire
		(pts
			(xy 344.17 210.82) (xy 344.17 212.09)
		)
		(stroke
			(width 0)
			(type default)
		)
	)
	(wire
		(pts
			(xy 251.46 81.28) (xy 262.89 81.28)
		)
		(stroke
			(width 0)
			(type default)
		)
	)
	(wire
		(pts
			(xy 251.46 71.12) (xy 269.24 71.12)
		)
		(stroke
			(width 0)
			(type default)
		)
	)
	(wire
		(pts
			(xy 375.92 52.07) (xy 375.92 59.69)
		)
		(stroke
			(width 0)
			(type default)
		)
	)
	(wire
		(pts
			(xy 160.02 41.91) (xy 160.02 43.18)
		)
		(stroke
			(width 0)
			(type default)
		)
	)
	(wire
		(pts
			(xy 106.68 41.91) (xy 106.68 43.18)
		)
		(stroke
			(width 0)
			(type default)
		)
	)
	(wire
		(pts
			(xy 290.83 177.8) (xy 290.83 181.61)
		)
		(stroke
			(width 0)
			(type default)
		)
	)
	(wire
		(pts
			(xy 163.83 55.88) (xy 163.83 57.15)
		)
		(stroke
			(width 0)
			(type default)
		)
	)
	(wire
		(pts
			(xy 214.63 190.5) (xy 218.44 190.5)
		)
		(stroke
			(width 0)
			(type default)
		)
	)
	(wire
		(pts
			(xy 360.68 201.93) (xy 360.68 203.2)
		)
		(stroke
			(width 0)
			(type default)
		)
	)
	(wire
		(pts
			(xy 128.27 227.33) (xy 128.27 229.87)
		)
		(stroke
			(width 0)
			(type default)
		)
	)
	(wire
		(pts
			(xy 378.46 44.45) (xy 375.92 44.45)
		)
		(stroke
			(width 0)
			(type default)
		)
	)
	(wire
		(pts
			(xy 193.04 226.06) (xy 193.04 227.33)
		)
		(stroke
			(width 0)
			(type default)
		)
	)
	(wire
		(pts
			(xy 391.16 226.06) (xy 391.16 228.6)
		)
		(stroke
			(width 0)
			(type default)
		)
	)
	(wire
		(pts
			(xy 124.46 39.37) (xy 133.35 39.37)
		)
		(stroke
			(width 0)
			(type default)
		)
	)
	(wire
		(pts
			(xy 165.1 243.84) (xy 165.1 246.38)
		)
		(stroke
			(width 0)
			(type default)
		)
	)
	(wire
		(pts
			(xy 203.2 271.78) (xy 203.2 274.32)
		)
		(stroke
			(width 0)
			(type default)
		)
	)
	(wire
		(pts
			(xy 182.88 187.96) (xy 182.88 194.31)
		)
		(stroke
			(width 0)
			(type default)
		)
	)
	(wire
		(pts
			(xy 132.08 72.39) (xy 138.43 72.39)
		)
		(stroke
			(width 0)
			(type default)
		)
	)
	(wire
		(pts
			(xy 368.3 80.01) (xy 368.3 77.47)
		)
		(stroke
			(width 0)
			(type default)
		)
	)
	(wire
		(pts
			(xy 124.46 33.02) (xy 124.46 31.75)
		)
		(stroke
			(width 0)
			(type default)
		)
	)
	(wire
		(pts
			(xy 375.92 52.07) (xy 378.46 52.07)
		)
		(stroke
			(width 0)
			(type default)
		)
	)
	(wire
		(pts
			(xy 106.68 48.26) (xy 106.68 49.53)
		)
		(stroke
			(width 0)
			(type default)
		)
	)
	(wire
		(pts
			(xy 153.67 190.5) (xy 156.21 190.5)
		)
		(stroke
			(width 0)
			(type default)
		)
	)
	(wire
		(pts
			(xy 236.22 187.96) (xy 236.22 201.93)
		)
		(stroke
			(width 0)
			(type default)
		)
	)
	(wire
		(pts
			(xy 360.68 208.28) (xy 360.68 215.9)
		)
		(stroke
			(width 0)
			(type default)
		)
	)
	(wire
		(pts
			(xy 236.22 217.17) (xy 251.46 217.17)
		)
		(stroke
			(width 0)
			(type default)
		)
	)
	(wire
		(pts
			(xy 251.46 67.31) (xy 262.89 67.31)
		)
		(stroke
			(width 0)
			(type default)
		)
	)
	(wire
		(pts
			(xy 194.31 69.85) (xy 168.91 69.85)
		)
		(stroke
			(width 0)
			(type default)
		)
	)
	(wire
		(pts
			(xy 133.35 39.37) (xy 142.24 39.37)
		)
		(stroke
			(width 0)
			(type default)
		)
	)
	(wire
		(pts
			(xy 185.42 238.76) (xy 199.39 238.76)
		)
		(stroke
			(width 0)
			(type default)
		)
	)
	(wire
		(pts
			(xy 92.71 259.08) (xy 92.71 256.54)
		)
		(stroke
			(width 0)
			(type default)
		)
	)
	(wire
		(pts
			(xy 185.42 29.21) (xy 185.42 31.75)
		)
		(stroke
			(width 0)
			(type default)
		)
	)
	(wire
		(pts
			(xy 101.6 204.47) (xy 104.14 204.47)
		)
		(stroke
			(width 0)
			(type default)
		)
	)
	(wire
		(pts
			(xy 274.32 234.95) (xy 274.32 189.23)
		)
		(stroke
			(width 0)
			(type default)
		)
	)
	(wire
		(pts
			(xy 375.92 36.83) (xy 375.92 44.45)
		)
		(stroke
			(width 0)
			(type default)
		)
	)
	(wire
		(pts
			(xy 323.85 156.21) (xy 323.85 157.48)
		)
		(stroke
			(width 0)
			(type default)
		)
	)
	(wire
		(pts
			(xy 124.46 49.53) (xy 133.35 49.53)
		)
		(stroke
			(width 0)
			(type default)
		)
	)
	(wire
		(pts
			(xy 128.27 201.93) (xy 128.27 218.44)
		)
		(stroke
			(width 0)
			(type default)
		)
	)
	(wire
		(pts
			(xy 82.55 114.3) (xy 82.55 113.03)
		)
		(stroke
			(width 0)
			(type default)
		)
	)
	(wire
		(pts
			(xy 193.04 118.11) (xy 193.04 115.57)
		)
		(stroke
			(width 0)
			(type default)
		)
	)
	(wire
		(pts
			(xy 88.9 204.47) (xy 88.9 210.82)
		)
		(stroke
			(width 0)
			(type default)
		)
	)
	(wire
		(pts
			(xy 179.07 217.17) (xy 210.82 217.17)
		)
		(stroke
			(width 0)
			(type default)
		)
	)
	(wire
		(pts
			(xy 128.27 201.93) (xy 182.88 201.93)
		)
		(stroke
			(width 0)
			(type default)
		)
	)
	(wire
		(pts
			(xy 121.92 243.84) (xy 118.11 243.84)
		)
		(stroke
			(width 0)
			(type default)
		)
	)
	(wire
		(pts
			(xy 214.63 187.96) (xy 236.22 187.96)
		)
		(stroke
			(width 0)
			(type default)
		)
	)
	(wire
		(pts
			(xy 82.55 31.75) (xy 97.79 31.75)
		)
		(stroke
			(width 0)
			(type default)
		)
	)
	(wire
		(pts
			(xy 290.83 177.8) (xy 298.45 177.8)
		)
		(stroke
			(width 0)
			(type default)
		)
	)
	(wire
		(pts
			(xy 213.36 209.55) (xy 213.36 210.82)
		)
		(stroke
			(width 0)
			(type default)
		)
	)
	(wire
		(pts
			(xy 151.13 41.91) (xy 160.02 41.91)
		)
		(stroke
			(width 0)
			(type default)
		)
	)
	(wire
		(pts
			(xy 170.18 41.91) (xy 170.18 43.18)
		)
		(stroke
			(width 0)
			(type default)
		)
	)
	(wire
		(pts
			(xy 336.55 231.14) (xy 336.55 232.41)
		)
		(stroke
			(width 0)
			(type default)
		)
	)
	(wire
		(pts
			(xy 182.88 201.93) (xy 186.69 201.93)
		)
		(stroke
			(width 0)
			(type default)
		)
	)
	(wire
		(pts
			(xy 76.2 246.38) (xy 83.82 246.38)
		)
		(stroke
			(width 0)
			(type default)
		)
	)
	(wire
		(pts
			(xy 38.1 160.02) (xy 38.1 161.29)
		)
		(stroke
			(width 0)
			(type default)
		)
	)
	(wire
		(pts
			(xy 151.13 49.53) (xy 160.02 49.53)
		)
		(stroke
			(width 0)
			(type default)
		)
	)
	(wire
		(pts
			(xy 82.55 31.75) (xy 82.55 35.56)
		)
		(stroke
			(width 0)
			(type default)
		)
	)
	(wire
		(pts
			(xy 227.33 151.13) (xy 227.33 149.86)
		)
		(stroke
			(width 0)
			(type default)
		)
	)
	(wire
		(pts
			(xy 236.22 207.01) (xy 236.22 217.17)
		)
		(stroke
			(width 0)
			(type default)
		)
	)
	(wire
		(pts
			(xy 227.33 139.7) (xy 227.33 149.86)
		)
		(stroke
			(width 0)
			(type default)
		)
	)
	(wire
		(pts
			(xy 383.54 223.52) (xy 384.81 223.52)
		)
		(stroke
			(width 0)
			(type default)
		)
	)
	(wire
		(pts
			(xy 170.18 31.75) (xy 179.07 31.75)
		)
		(stroke
			(width 0)
			(type default)
		)
	)
	(wire
		(pts
			(xy 236.22 241.3) (xy 236.22 266.7)
		)
		(stroke
			(width 0)
			(type default)
		)
	)
	(wire
		(pts
			(xy 156.21 190.5) (xy 166.37 190.5)
		)
		(stroke
			(width 0)
			(type default)
		)
	)
	(wire
		(pts
			(xy 115.57 48.26) (xy 115.57 49.53)
		)
		(stroke
			(width 0)
			(type default)
		)
	)
	(wire
		(pts
			(xy 274.32 234.95) (xy 284.48 234.95)
		)
		(stroke
			(width 0)
			(type default)
		)
	)
	(wire
		(pts
			(xy 142.24 41.91) (xy 142.24 43.18)
		)
		(stroke
			(width 0)
			(type default)
		)
	)
	(wire
		(pts
			(xy 185.42 31.75) (xy 185.42 64.77)
		)
		(stroke
			(width 0)
			(type default)
		)
	)
	(wire
		(pts
			(xy 317.5 187.96) (xy 317.5 177.8)
		)
		(stroke
			(width 0)
			(type default)
		)
	)
	(wire
		(pts
			(xy 30.48 153.67) (xy 33.02 153.67)
		)
		(stroke
			(width 0)
			(type default)
		)
	)
	(wire
		(pts
			(xy 179.07 31.75) (xy 179.07 41.91)
		)
		(stroke
			(width 0)
			(type default)
		)
	)
	(wire
		(pts
			(xy 54.61 86.36) (xy 54.61 87.63)
		)
		(stroke
			(width 0)
			(type default)
		)
	)
	(wire
		(pts
			(xy 143.51 72.39) (xy 148.59 72.39)
		)
		(stroke
			(width 0)
			(type default)
		)
	)
	(wire
		(pts
			(xy 354.33 233.68) (xy 354.33 223.52)
		)
		(stroke
			(width 0)
			(type default)
		)
	)
	(wire
		(pts
			(xy 375.92 208.28) (xy 375.92 215.9)
		)
		(stroke
			(width 0)
			(type default)
		)
	)
	(wire
		(pts
			(xy 85.09 162.56) (xy 85.09 160.02)
		)
		(stroke
			(width 0)
			(type default)
		)
	)
	(wire
		(pts
			(xy 251.46 64.77) (xy 273.05 64.77)
		)
		(stroke
			(width 0)
			(type default)
		)
	)
	(wire
		(pts
			(xy 151.13 39.37) (xy 151.13 38.1)
		)
		(stroke
			(width 0)
			(type default)
		)
	)
	(wire
		(pts
			(xy 54.61 80.01) (xy 54.61 81.28)
		)
		(stroke
			(width 0)
			(type default)
		)
	)
	(wire
		(pts
			(xy 195.58 39.37) (xy 204.47 39.37)
		)
		(stroke
			(width 0)
			(type default)
		)
	)
	(wire
		(pts
			(xy 118.11 229.87) (xy 128.27 229.87)
		)
		(stroke
			(width 0)
			(type default)
		)
	)
	(wire
		(pts
			(xy 124.46 31.75) (xy 115.57 31.75)
		)
		(stroke
			(width 0)
			(type default)
		)
	)
	(wire
		(pts
			(xy 124.46 31.75) (xy 133.35 31.75)
		)
		(stroke
			(width 0)
			(type default)
		)
	)
	(wire
		(pts
			(xy 83.82 246.38) (xy 100.33 246.38)
		)
		(stroke
			(width 0)
			(type default)
		)
	)
	(wire
		(pts
			(xy 128.27 246.38) (xy 128.27 259.08)
		)
		(stroke
			(width 0)
			(type default)
		)
	)
	(wire
		(pts
			(xy 58.42 256.54) (xy 58.42 259.08)
		)
		(stroke
			(width 0)
			(type default)
		)
	)
	(wire
		(pts
			(xy 213.36 233.68) (xy 213.36 234.95)
		)
		(stroke
			(width 0)
			(type default)
		)
	)
	(wire
		(pts
			(xy 88.9 204.47) (xy 88.9 201.93)
		)
		(stroke
			(width 0)
			(type default)
		)
	)
	(wire
		(pts
			(xy 78.74 101.6) (xy 71.12 101.6)
		)
		(stroke
			(width 0)
			(type default)
		)
	)
	(wire
		(pts
			(xy 182.88 199.39) (xy 182.88 201.93)
		)
		(stroke
			(width 0)
			(type default)
		)
	)
	(wire
		(pts
			(xy 360.68 226.06) (xy 360.68 228.6)
		)
		(stroke
			(width 0)
			(type default)
		)
	)
	(wire
		(pts
			(xy 39.37 31.75) (xy 52.07 31.75)
		)
		(stroke
			(width 0)
			(type default)
		)
	)
	(wire
		(pts
			(xy 220.98 31.75) (xy 220.98 33.02)
		)
		(stroke
			(width 0)
			(type default)
		)
	)
	(wire
		(pts
			(xy 180.34 274.32) (xy 196.85 274.32)
		)
		(stroke
			(width 0)
			(type default)
		)
	)
	(wire
		(pts
			(xy 231.14 266.7) (xy 236.22 266.7)
		)
		(stroke
			(width 0)
			(type default)
		)
	)
	(wire
		(pts
			(xy 109.22 201.93) (xy 109.22 204.47)
		)
		(stroke
			(width 0)
			(type default)
		)
	)
	(wire
		(pts
			(xy 186.69 193.04) (xy 186.69 201.93)
		)
		(stroke
			(width 0)
			(type default)
		)
	)
	(wire
		(pts
			(xy 38.1 144.78) (xy 38.1 147.32)
		)
		(stroke
			(width 0)
			(type default)
		)
	)
	(wire
		(pts
			(xy 219.71 193.04) (xy 218.44 193.04)
		)
		(stroke
			(width 0)
			(type default)
		)
	)
	(wire
		(pts
			(xy 83.82 153.67) (xy 96.52 153.67)
		)
		(stroke
			(width 0)
			(type default)
		)
	)
	(wire
		(pts
			(xy 212.09 31.75) (xy 220.98 31.75)
		)
		(stroke
			(width 0)
			(type default)
		)
	)
	(wire
		(pts
			(xy 363.22 85.09) (xy 363.22 87.63)
		)
		(stroke
			(width 0)
			(type default)
		)
	)
	(wire
		(pts
			(xy 48.26 157.48) (xy 64.77 157.48)
		)
		(stroke
			(width 0)
			(type default)
		)
	)
	(wire
		(pts
			(xy 336.55 232.41) (xy 336.55 233.68)
		)
		(stroke
			(width 0)
			(type default)
		)
	)
	(wire
		(pts
			(xy 378.46 36.83) (xy 375.92 36.83)
		)
		(stroke
			(width 0)
			(type default)
		)
	)
	(wire
		(pts
			(xy 124.46 41.91) (xy 115.57 41.91)
		)
		(stroke
			(width 0)
			(type default)
		)
	)
	(wire
		(pts
			(xy 290.83 156.21) (xy 290.83 157.48)
		)
		(stroke
			(width 0)
			(type default)
		)
	)
	(wire
		(pts
			(xy 71.12 101.6) (xy 71.12 105.41)
		)
		(stroke
			(width 0)
			(type default)
		)
	)
	(wire
		(pts
			(xy 290.83 162.56) (xy 290.83 177.8)
		)
		(stroke
			(width 0)
			(type default)
		)
	)
	(wire
		(pts
			(xy 185.42 226.06) (xy 193.04 226.06)
		)
		(stroke
			(width 0)
			(type default)
		)
	)
	(wire
		(pts
			(xy 156.21 180.34) (xy 156.21 182.88)
		)
		(stroke
			(width 0)
			(type default)
		)
	)
	(wire
		(pts
			(xy 133.35 49.53) (xy 142.24 49.53)
		)
		(stroke
			(width 0)
			(type default)
		)
	)
	(wire
		(pts
			(xy 85.09 101.6) (xy 90.17 101.6)
		)
		(stroke
			(width 0)
			(type default)
		)
	)
	(wire
		(pts
			(xy 115.57 41.91) (xy 106.68 41.91)
		)
		(stroke
			(width 0)
			(type default)
		)
	)
	(wire
		(pts
			(xy 205.74 187.96) (xy 209.55 187.96)
		)
		(stroke
			(width 0)
			(type default)
		)
	)
	(wire
		(pts
			(xy 101.6 201.93) (xy 104.14 201.93)
		)
		(stroke
			(width 0)
			(type default)
		)
	)
	(wire
		(pts
			(xy 227.33 139.7) (xy 228.6 139.7)
		)
		(stroke
			(width 0)
			(type default)
		)
	)
	(wire
		(pts
			(xy 335.28 77.47) (xy 356.87 77.47)
		)
		(stroke
			(width 0)
			(type default)
		)
	)
	(wire
		(pts
			(xy 185.42 241.3) (xy 210.82 241.3)
		)
		(stroke
			(width 0)
			(type default)
		)
	)
	(wire
		(pts
			(xy 124.46 41.91) (xy 133.35 41.91)
		)
		(stroke
			(width 0)
			(type default)
		)
	)
	(wire
		(pts
			(xy 201.93 152.4) (xy 207.01 152.4)
		)
		(stroke
			(width 0)
			(type default)
		)
	)
	(wire
		(pts
			(xy 142.24 33.02) (xy 142.24 31.75)
		)
		(stroke
			(width 0)
			(type default)
		)
	)
	(wire
		(pts
			(xy 33.02 153.67) (xy 38.1 153.67)
		)
		(stroke
			(width 0)
			(type default)
		)
	)
	(wire
		(pts
			(xy 179.07 41.91) (xy 179.07 67.31)
		)
		(stroke
			(width 0)
			(type default)
		)
	)
	(wire
		(pts
			(xy 166.37 187.96) (xy 166.37 190.5)
		)
		(stroke
			(width 0)
			(type default)
		)
	)
	(wire
		(pts
			(xy 163.83 57.15) (xy 163.83 58.42)
		)
		(stroke
			(width 0)
			(type default)
		)
	)
	(wire
		(pts
			(xy 214.63 144.78) (xy 214.63 153.67)
		)
		(stroke
			(width 0)
			(type default)
		)
	)
	(wire
		(pts
			(xy 182.88 176.53) (xy 179.07 176.53)
		)
		(stroke
			(width 0)
			(type default)
		)
	)
	(wire
		(pts
			(xy 97.79 175.26) (xy 125.73 175.26)
		)
		(stroke
			(width 0)
			(type default)
		)
	)
	(wire
		(pts
			(xy 363.22 77.47) (xy 363.22 80.01)
		)
		(stroke
			(width 0)
			(type default)
		)
	)
	(wire
		(pts
			(xy 344.17 220.98) (xy 344.17 224.79)
		)
		(stroke
			(width 0)
			(type default)
		)
	)
	(wire
		(pts
			(xy 199.39 247.65) (xy 199.39 248.92)
		)
		(stroke
			(width 0)
			(type default)
		)
	)
	(wire
		(pts
			(xy 33.02 157.48) (xy 33.02 153.67)
		)
		(stroke
			(width 0)
			(type default)
		)
	)
	(wire
		(pts
			(xy 115.57 31.75) (xy 106.68 31.75)
		)
		(stroke
			(width 0)
			(type default)
		)
	)
	(wire
		(pts
			(xy 189.23 91.44) (xy 194.31 91.44)
		)
		(stroke
			(width 0)
			(type default)
		)
	)
	(wire
		(pts
			(xy 186.69 193.04) (xy 187.96 193.04)
		)
		(stroke
			(width 0)
			(type default)
		)
	)
	(wire
		(pts
			(xy 99.06 233.68) (xy 95.25 233.68)
		)
		(stroke
			(width 0)
			(type default)
		)
	)
	(wire
		(pts
			(xy 193.04 224.79) (xy 193.04 226.06)
		)
		(stroke
			(width 0)
			(type default)
		)
	)
	(wire
		(pts
			(xy 179.07 29.21) (xy 179.07 31.75)
		)
		(stroke
			(width 0)
			(type default)
		)
	)
	(wire
		(pts
			(xy 142.24 49.53) (xy 151.13 49.53)
		)
		(stroke
			(width 0)
			(type default)
		)
	)
	(wire
		(pts
			(xy 236.22 187.96) (xy 236.22 184.15)
		)
		(stroke
			(width 0)
			(type default)
		)
	)
	(wire
		(pts
			(xy 231.14 217.17) (xy 236.22 217.17)
		)
		(stroke
			(width 0)
			(type default)
		)
	)
	(wire
		(pts
			(xy 142.24 39.37) (xy 151.13 39.37)
		)
		(stroke
			(width 0)
			(type default)
		)
	)
	(wire
		(pts
			(xy 187.96 39.37) (xy 195.58 39.37)
		)
		(stroke
			(width 0)
			(type default)
		)
	)
	(wire
		(pts
			(xy 88.9 204.47) (xy 91.44 204.47)
		)
		(stroke
			(width 0)
			(type default)
		)
	)
	(wire
		(pts
			(xy 30.48 157.48) (xy 33.02 157.48)
		)
		(stroke
			(width 0)
			(type default)
		)
	)
	(wire
		(pts
			(xy 82.55 30.48) (xy 82.55 31.75)
		)
		(stroke
			(width 0)
			(type default)
		)
	)
	(wire
		(pts
			(xy 76.2 31.75) (xy 82.55 31.75)
		)
		(stroke
			(width 0)
			(type default)
		)
	)
	(wire
		(pts
			(xy 391.16 208.28) (xy 391.16 215.9)
		)
		(stroke
			(width 0)
			(type default)
		)
	)
	(wire
		(pts
			(xy 96.52 153.67) (xy 96.52 154.94)
		)
		(stroke
			(width 0)
			(type default)
		)
	)
	(wire
		(pts
			(xy 154.94 72.39) (xy 194.31 72.39)
		)
		(stroke
			(width 0)
			(type default)
		)
	)
	(wire
		(pts
			(xy 85.09 114.3) (xy 85.09 115.57)
		)
		(stroke
			(width 0)
			(type default)
		)
	)
	(wire
		(pts
			(xy 179.07 67.31) (xy 194.31 67.31)
		)
		(stroke
			(width 0)
			(type default)
		)
	)
	(label "~{SOM_PRSNT}"
		(at 180.34 274.32 0)
		(effects
			(font
				(size 1.27 1.27)
			)
			(justify left bottom)
		)
	)
	(label "~{VDDIN_PWR_BAD}"
		(at 176.53 85.09 0)
		(effects
			(font
				(size 1.27 1.27)
			)
			(justify left bottom)
		)
	)
	(label "~{MOD_SLEEP}"
		(at 262.89 81.28 180)
		(effects
			(font
				(size 1.27 1.27)
			)
			(justify right bottom)
		)
	)
	(label "MODULE_POWER_ON"
		(at 273.05 64.77 180)
		(effects
			(font
				(size 1.27 1.27)
			)
			(justify right bottom)
		)
	)
	(label "~{PWR_BTN}"
		(at 133.35 201.93 0)
		(effects
			(font
				(size 1.27 1.27)
			)
			(justify left bottom)
		)
	)
	(label "~{SOM_POWER_BTN}"
		(at 234.95 190.5 180)
		(effects
			(font
				(size 1.27 1.27)
			)
			(justify right bottom)
		)
	)
	(label "~{FORCE_RECOVERY}"
		(at 194.31 142.24 0)
		(effects
			(font
				(size 1.27 1.27)
			)
			(justify left bottom)
		)
	)
	(label "~{SYS_RESET}"
		(at 104.14 101.6 180)
		(effects
			(font
				(size 1.27 1.27)
			)
			(justify right bottom)
		)
	)
	(label "~{SOM_POWER_BTN}"
		(at 269.24 71.12 180)
		(effects
			(font
				(size 1.27 1.27)
			)
			(justify right bottom)
		)
	)
	(label "~{FORCE_RECOVERY}"
		(at 335.28 77.47 0)
		(effects
			(font
				(size 1.27 1.27)
			)
			(justify left bottom)
		)
	)
	(label "MODULE_POWER_ON"
		(at 120.65 153.67 180)
		(effects
			(font
				(size 1.27 1.27)
			)
			(justify right bottom)
		)
	)
	(label "MODULE_POWER_ON"
		(at 146.05 236.22 0)
		(effects
			(font
				(size 1.27 1.27)
			)
			(justify left bottom)
		)
	)
	(label "~{SLEEP_REQ}"
		(at 262.89 78.74 180)
		(effects
			(font
				(size 1.27 1.27)
			)
			(justify right bottom)
		)
	)
	(label "VIN_PWR_ON"
		(at 34.29 48.26 0)
		(effects
			(font
				(size 1.27 1.27)
			)
			(justify left bottom)
		)
	)
	(label "~{SYS_RESET}"
		(at 176.53 82.55 0)
		(effects
			(font
				(size 1.27 1.27)
			)
			(justify left bottom)
		)
	)
	(label "~{PWR_BTN}"
		(at 194.31 147.32 0)
		(effects
			(font
				(size 1.27 1.27)
			)
			(justify left bottom)
		)
	)
	(label "~{SYS_RESET}"
		(at 194.31 144.78 0)
		(effects
			(font
				(size 1.27 1.27)
			)
			(justify left bottom)
		)
	)
	(label "~{FORCE_SHDN}"
		(at 251.46 217.17 180)
		(effects
			(font
				(size 1.27 1.27)
			)
			(justify right bottom)
		)
	)
	(label "~{SOM_PRSNT}"
		(at 176.53 88.9 0)
		(effects
			(font
				(size 1.27 1.27)
			)
			(justify left bottom)
		)
	)
	(label "~{MODULE_SHDN}"
		(at 179.07 217.17 0)
		(effects
			(font
				(size 1.27 1.27)
			)
			(justify left bottom)
		)
	)
	(label "VIN_PWR_ON"
		(at 111.76 175.26 0)
		(effects
			(font
				(size 1.27 1.27)
			)
			(justify left bottom)
		)
	)
	(label "~{MODULE_SHDN}"
		(at 276.86 93.98 180)
		(effects
			(font
				(size 1.27 1.27)
			)
			(justify right bottom)
		)
	)
	(label "~{FORCE_RECOVERY}"
		(at 269.24 76.2 180)
		(effects
			(font
				(size 1.27 1.27)
			)
			(justify right bottom)
		)
	)
	(label "~{FORCE_SHDN}"
		(at 48.26 157.48 0)
		(effects
			(font
				(size 1.27 1.27)
			)
			(justify left bottom)
		)
	)
	(label "~{VDDIN_PWR_BAD}"
		(at 63.5 153.67 180)
		(effects
			(font
				(size 1.27 1.27)
			)
			(justify right bottom)
		)
	)
	(label "SYS_VIN_HV_SOM"
		(at 245.11 31.75 0)
		(effects
			(font
				(size 1.27 1.27)
			)
			(justify left bottom)
		)
	)
	(hierarchical_label "VIN_PWR_ON"
		(shape output)
		(at 125.73 175.26 0)
		(effects
			(font
				(size 1.27 1.27)
			)
			(justify left)
		)
	)
	(hierarchical_label "CARRIER_PWR_ON"
		(shape output)
		(at 262.89 67.31 0)
		(effects
			(font
				(size 1.27 1.27)
			)
			(justify left)
		)
	)
	(hierarchical_label "CARRIER_PWR_ON"
		(shape output)
		(at 327.66 232.41 180)
		(effects
			(font
				(size 1.27 1.27)
			)
			(justify right)
		)
	)
	(hierarchical_label "~{VDDIN_PWR_BAD}"
		(shape input)
		(at 30.48 153.67 180)
		(effects
			(font
				(size 1.27 1.27)
			)
			(justify right)
		)
	)
	(hierarchical_label "VIN_PWR_ON"
		(shape output)
		(at 273.05 189.23 180)
		(effects
			(font
				(size 1.27 1.27)
			)
			(justify right)
		)
	)
	(symbol
		(lib_id "antmicropower:GND")
		(at 163.83 63.5 0)
		(mirror y)
		(unit 1)
		(exclude_from_sim no)
		(in_bom yes)
		(on_board yes)
		(dnp no)
		(property "Reference" "#PWR048"
			(at 154.94 66.04 0)
			(effects
				(font
					(size 1.27 1.27)
					(thickness 0.15)
				)
				(justify left bottom)
				(hide yes)
			)
		)
		(property "Value" "GND"
			(at 163.83 67.31 0)
			(effects
				(font
					(size 1.27 1.27)
					(thickness 0.15)
				)
			)
		)
		(property "Footprint" ""
			(at 154.94 71.12 0)
			(effects
				(font
					(size 1.27 1.27)
					(thickness 0.15)
				)
				(justify left bottom)
				(hide yes)
			)
		)
		(property "Datasheet" ""
			(at 154.94 76.2 0)
			(effects
				(font
					(size 1.27 1.27)
					(thickness 0.15)
				)
				(justify left bottom)
				(hide yes)
			)
		)
		(property "Description" ""
			(at 163.83 63.5 0)
			(effects
				(font
					(size 1.27 1.27)
				)
				(hide yes)
			)
		)
		(property "Author" "Antmicro"
			(at 154.94 71.12 0)
			(effects
				(font
					(size 1.27 1.27)
					(thickness 0.15)
				)
				(justify left bottom)
				(hide yes)
			)
		)
		(property "License" "Apache-2.0"
			(at 154.94 73.66 0)
			(effects
				(font
					(size 1.27 1.27)
					(thickness 0.15)
				)
				(justify left bottom)
				(hide yes)
			)
		)
		(pin "1"
		)
		(instances
			(project "jetson-agx-thor-baseboard"
				(path ""
					(reference "#PWR048")
					(unit 1)
				)
			)
		)
	)
	(symbol
		(lib_id "antmicroCapacitors0603:C_22u_16V_0603")
		(at 124.46 38.1 90)
		(unit 1)
		(exclude_from_sim no)
		(in_bom yes)
		(on_board yes)
		(dnp no)
		(property "Reference" "C21"
			(at 127 34.2836 90)
			(effects
				(font
					(size 1.27 1.27)
					(thickness 0.15)
				)
				(justify right)
			)
		)
		(property "Value" "C_22u_16V_0603"
			(at 134.62 17.78 0)
			(effects
				(font
					(size 1.27 1.27)
					(thickness 0.15)
				)
				(justify left bottom)
				(hide yes)
			)
		)
		(property "Footprint" "antmicro-footprints:C_0603_1608Metric_EIA"
			(at 137.16 17.78 0)
			(effects
				(font
					(size 1.27 1.27)
					(thickness 0.15)
				)
				(justify left bottom)
				(hide yes)
			)
		)
		(property "Datasheet" "https://product.samsungsem.com/mlcc/CL10A226MO7JZN.do"
			(at 139.7 17.78 0)
			(effects
				(font
					(size 1.27 1.27)
					(thickness 0.15)
				)
				(justify left bottom)
				(hide yes)
			)
		)
		(property "Description" "SMD Multilayer Ceramic Capacitor"
			(at 124.46 38.1 0)
			(effects
				(font
					(size 1.27 1.27)
				)
				(hide yes)
			)
		)
		(property "MPN" "CL10A226MO7JZNC"
			(at 142.24 17.78 0)
			(effects
				(font
					(size 1.27 1.27)
					(thickness 0.15)
				)
				(justify left bottom)
				(hide yes)
			)
		)
		(property "Manufacturer" "Samsung Electro-Mechanics"
			(at 144.78 17.78 0)
			(effects
				(font
					(size 1.27 1.27)
					(thickness 0.15)
				)
				(justify left bottom)
				(hide yes)
			)
		)
		(property "License" "Apache-2.0"
			(at 147.32 17.78 0)
			(effects
				(font
					(size 1.27 1.27)
					(thickness 0.15)
				)
				(justify left bottom)
				(hide yes)
			)
		)
		(property "Author" "Antmicro"
			(at 149.86 17.78 0)
			(effects
				(font
					(size 1.27 1.27)
					(thickness 0.15)
				)
				(justify left bottom)
				(hide yes)
			)
		)
		(property "Val" "22u"
			(at 127 36.8236 90)
			(effects
				(font
					(size 1.27 1.27)
					(thickness 0.15)
				)
				(justify right)
			)
		)
		(property "Voltage" "16V"
			(at 152.4 17.78 0)
			(effects
				(font
					(size 1.27 1.27)
				)
				(justify left bottom)
				(hide yes)
			)
		)
		(property "Dielectric" "X7R"
			(at 154.94 17.78 0)
			(effects
				(font
					(size 1.27 1.27)
				)
				(justify left bottom)
				(hide yes)
			)
		)
		(property "Public" "False"
			(at 157.48 17.78 0)
			(effects
				(font
					(size 1.27 1.27)
				)
				(justify left bottom)
				(hide yes)
			)
		)
		(pin "1"
		)
		(pin "2"
		)
		(instances
			(project "jetson-agx-thor-baseboard"
				(path ""
					(reference "C21")
					(unit 1)
				)
			)
		)
	)
	(symbol
		(lib_id "antmicroResistors0402:R_10k_0402")
		(at 236.22 207.01 90)
		(unit 1)
		(exclude_from_sim no)
		(in_bom yes)
		(on_board yes)
		(dnp no)
		(property "Reference" "R300"
			(at 237.49 203.2 90)
			(effects
				(font
					(size 1.27 1.27)
					(thickness 0.15)
				)
				(justify right)
			)
		)
		(property "Value" "R_10k_0402"
			(at 248.92 186.69 0)
			(effects
				(font
					(size 1.27 1.27)
					(thickness 0.15)
				)
				(justify left bottom)
				(hide yes)
			)
		)
		(property "Footprint" "antmicro-footprints:R_0402_1005Metric"
			(at 251.46 186.69 0)
			(effects
				(font
					(size 1.27 1.27)
					(thickness 0.15)
				)
				(justify left bottom)
				(hide yes)
			)
		)
		(property "Datasheet" "https://www.bourns.com/docs/product-datasheets/cr.pdf"
			(at 254 186.69 0)
			(effects
				(font
					(size 1.27 1.27)
					(thickness 0.15)
				)
				(justify left bottom)
				(hide yes)
			)
		)
		(property "Description" "SMD Chip Resistor, 10 kohm, ± 1%, 62.5 mW, 0402 [1005 Metric], Thick Film, General Purpose"
			(at 236.22 207.01 0)
			(effects
				(font
					(size 1.27 1.27)
				)
				(hide yes)
			)
		)
		(property "MPN" "CR0402-FX-1002GLF"
			(at 256.54 186.69 0)
			(effects
				(font
					(size 1.27 1.27)
					(thickness 0.15)
				)
				(justify left bottom)
				(hide yes)
			)
		)
		(property "Manufacturer" "Bourns"
			(at 259.08 186.69 0)
			(effects
				(font
					(size 1.27 1.27)
					(thickness 0.15)
				)
				(justify left bottom)
				(hide yes)
			)
		)
		(property "License" "Apache-2.0"
			(at 261.62 186.69 0)
			(effects
				(font
					(size 1.27 1.27)
					(thickness 0.15)
				)
				(justify left bottom)
				(hide yes)
			)
		)
		(property "Author" "Antmicro"
			(at 264.16 186.69 0)
			(effects
				(font
					(size 1.27 1.27)
					(thickness 0.15)
				)
				(justify left bottom)
				(hide yes)
			)
		)
		(property "Val" "10k"
			(at 237.49 205.74 90)
			(effects
				(font
					(size 1.27 1.27)
					(thickness 0.15)
				)
				(justify right)
			)
		)
		(property "Tolerance" "1%"
			(at 246.38 186.69 0)
			(effects
				(font
					(size 1.27 1.27)
				)
				(justify left bottom)
				(hide yes)
			)
		)
		(pin "2"
		)
		(pin "1"
		)
		(instances
			(project "jetson-agx-thor-baseboard"
				(path ""
					(reference "R300")
					(unit 1)
				)
			)
		)
	)
	(symbol
		(lib_id "antmicroTestPoints:TP_0.75mm_SMD")
		(at 251.46 105.41 0)
		(unit 1)
		(exclude_from_sim no)
		(in_bom no)
		(on_board yes)
		(dnp no)
		(fields_autoplaced yes)
		(property "Reference" "TP56"
			(at 256.54 105.41 0)
			(effects
				(font
					(size 1.27 1.27)
					(thickness 0.15)
				)
				(justify left)
			)
		)
		(property "Value" "TP_0.75mm_SMD"
			(at 261.62 109.22 0)
			(effects
				(font
					(size 1.27 1.27)
					(thickness 0.15)
				)
				(justify left bottom)
				(hide yes)
			)
		)
		(property "Footprint" "antmicro-footprints:TP_SMD_0.75mm"
			(at 261.62 111.76 0)
			(effects
				(font
					(size 1.27 1.27)
					(thickness 0.15)
				)
				(justify left bottom)
				(hide yes)
			)
		)
		(property "Datasheet" ""
			(at 269.24 118.11 0)
			(effects
				(font
					(size 1.27 1.27)
					(thickness 0.15)
				)
				(justify left bottom)
				(hide yes)
			)
		)
		(property "Description" "SMT test point"
			(at 251.46 105.41 0)
			(effects
				(font
					(size 1.27 1.27)
				)
				(hide yes)
			)
		)
		(property "MPN" ""
			(at 262.255 116.84 0)
			(effects
				(font
					(size 1.27 1.27)
					(thickness 0.15)
				)
				(justify left bottom)
				(hide yes)
			)
		)
		(property "Manufacturer" ""
			(at 262.255 111.76 0)
			(effects
				(font
					(size 1.27 1.27)
					(thickness 0.15)
				)
				(justify left bottom)
				(hide yes)
			)
		)
		(property "Author" "Antmicro"
			(at 261.62 114.3 0)
			(effects
				(font
					(size 1.27 1.27)
					(thickness 0.15)
				)
				(justify left bottom)
				(hide yes)
			)
		)
		(property "License" "Apache-2.0"
			(at 261.62 116.84 0)
			(effects
				(font
					(size 1.27 1.27)
					(thickness 0.15)
				)
				(justify left bottom)
				(hide yes)
			)
		)
		(pin "1"
		)
		(instances
			(project "jetson-agx-thor-baseboard"
				(path ""
					(reference "TP56")
					(unit 1)
				)
			)
		)
	)
	(symbol
		(lib_id "antmicroTransistorsFETsMOSFETsSingle:DMG1012T-7")
		(at 284.48 189.23 0)
		(unit 1)
		(exclude_from_sim no)
		(in_bom yes)
		(on_board yes)
		(dnp no)
		(property "Reference" "Q7"
			(at 294.64 187.452 0)
			(effects
				(font
					(size 1.27 1.27)
					(thickness 0.15)
				)
				(justify left)
			)
		)
		(property "Value" "DMG1012T-7"
			(at 307.34 198.12 0)
			(effects
				(font
					(size 1.27 1.27)
					(thickness 0.15)
				)
				(justify left bottom)
				(hide yes)
			)
		)
		(property "Footprint" "antmicro-footprints:SOT-523"
			(at 307.34 200.66 0)
			(effects
				(font
					(size 1.27 1.27)
					(thickness 0.15)
				)
				(justify left bottom)
				(hide yes)
			)
		)
		(property "Datasheet" "https://www.diodes.com/assets/Datasheets/ds31783.pdf"
			(at 307.34 203.2 0)
			(effects
				(font
					(size 1.27 1.27)
					(thickness 0.15)
				)
				(justify left bottom)
				(hide yes)
			)
		)
		(property "Description" "Power MOSFET, N Channel, 20 V, 630 mA, 0.3 ohm, SOT-523, Surface Mount"
			(at 307.34 215.9 0)
			(effects
				(font
					(size 1.27 1.27)
				)
				(justify left bottom)
				(hide yes)
			)
		)
		(property "MPN" "DMG1012T-7"
			(at 294.64 189.992 0)
			(effects
				(font
					(size 1.27 1.27)
					(thickness 0.15)
				)
				(justify left)
			)
		)
		(property "Manufacturer" "Diodes Incorporated"
			(at 307.34 208.28 0)
			(effects
				(font
					(size 1.27 1.27)
					(thickness 0.15)
				)
				(justify left bottom)
				(hide yes)
			)
		)
		(property "Author" "Antmicro"
			(at 307.34 210.82 0)
			(effects
				(font
					(size 1.27 1.27)
					(thickness 0.15)
				)
				(justify left bottom)
				(hide yes)
			)
		)
		(property "License" "Apache-2.0"
			(at 307.34 213.36 0)
			(effects
				(font
					(size 1.27 1.27)
					(thickness 0.15)
				)
				(justify left bottom)
				(hide yes)
			)
		)
		(pin "3"
		)
		(pin "1"
		)
		(pin "2"
		)
		(instances
			(project "jetson-agx-thor-baseboard"
				(path ""
					(reference "Q7")
					(unit 1)
				)
			)
		)
	)
	(symbol
		(lib_id "antmicroMechanicalParts:Lightpipe_Bivar_SLP3-150-150-F")
		(at 54.61 115.57 0)
		(mirror y)
		(unit 1)
		(exclude_from_sim no)
		(in_bom yes)
		(on_board yes)
		(dnp no)
		(fields_autoplaced yes)
		(property "Reference" "H14"
			(at 48.26 114.0017 0)
			(effects
				(font
					(size 1.27 1.27)
					(thickness 0.15)
				)
				(justify left)
			)
		)
		(property "Value" "Lightpipe_Bivar_SLP3-150-150-F"
			(at 42.85 122.885 0)
			(effects
				(font
					(size 1.27 1.27)
					(thickness 0.15)
				)
				(justify left bottom)
				(hide yes)
			)
		)
		(property "Footprint" "antmicro-footprints:Mech_Lightpipe_Bivar_SLP3-150-150-F"
			(at 42.85 125.425 0)
			(effects
				(font
					(size 1.27 1.27)
					(thickness 0.15)
				)
				(justify left bottom)
				(hide yes)
			)
		)
		(property "Datasheet" "https://eu.mouser.com/datasheet/2/50/Bivar_SLP3_150_XXX_X_N-3318840.pdf"
			(at 42.85 127.965 0)
			(effects
				(font
					(size 1.27 1.27)
					(thickness 0.15)
				)
				(justify left bottom)
				(hide yes)
			)
		)
		(property "Description" "LED Light Pipe, Rigid Board, Horizontal"
			(at 42.85 138.125 0)
			(effects
				(font
					(size 1.27 1.27)
				)
				(justify left bottom)
				(hide yes)
			)
		)
		(property "Manufacturer" "BIVAR"
			(at 42.85 130.505 0)
			(effects
				(font
					(size 1.27 1.27)
					(thickness 0.15)
				)
				(justify left bottom)
				(hide yes)
			)
		)
		(property "MPN" "SLP3-150-150-F"
			(at 48.26 116.5417 0)
			(effects
				(font
					(size 1.27 1.27)
					(thickness 0.15)
				)
				(justify left)
			)
		)
		(property "Author" "Antmicro"
			(at 42.85 133.045 0)
			(effects
				(font
					(size 1.27 1.27)
					(thickness 0.15)
				)
				(justify left bottom)
				(hide yes)
			)
		)
		(property "License" "Apache-2.0"
			(at 42.85 135.585 0)
			(effects
				(font
					(size 1.27 1.27)
					(thickness 0.15)
				)
				(justify left bottom)
				(hide yes)
			)
		)
		(instances
			(project ""
				(path ""
					(reference "H14")
					(unit 1)
				)
			)
		)
	)
	(symbol
		(lib_id "antmicroResistors0402:R_10k_0402")
		(at 166.37 187.96 90)
		(unit 1)
		(exclude_from_sim no)
		(in_bom no)
		(on_board yes)
		(dnp yes)
		(property "Reference" "R289"
			(at 167.64 184.15 90)
			(effects
				(font
					(size 1.27 1.27)
					(thickness 0.15)
				)
				(justify right)
			)
		)
		(property "Value" "R_10k_0402"
			(at 179.07 167.64 0)
			(effects
				(font
					(size 1.27 1.27)
					(thickness 0.15)
				)
				(justify left bottom)
				(hide yes)
			)
		)
		(property "Footprint" "antmicro-footprints:R_0402_1005Metric"
			(at 181.61 167.64 0)
			(effects
				(font
					(size 1.27 1.27)
					(thickness 0.15)
				)
				(justify left bottom)
				(hide yes)
			)
		)
		(property "Datasheet" "https://www.bourns.com/docs/product-datasheets/cr.pdf"
			(at 184.15 167.64 0)
			(effects
				(font
					(size 1.27 1.27)
					(thickness 0.15)
				)
				(justify left bottom)
				(hide yes)
			)
		)
		(property "Description" "SMD Chip Resistor, 10 kohm, ± 1%, 62.5 mW, 0402 [1005 Metric], Thick Film, General Purpose"
			(at 166.37 187.96 0)
			(effects
				(font
					(size 1.27 1.27)
				)
				(hide yes)
			)
		)
		(property "MPN" "CR0402-FX-1002GLF"
			(at 186.69 167.64 0)
			(effects
				(font
					(size 1.27 1.27)
					(thickness 0.15)
				)
				(justify left bottom)
				(hide yes)
			)
		)
		(property "Manufacturer" "Bourns"
			(at 189.23 167.64 0)
			(effects
				(font
					(size 1.27 1.27)
					(thickness 0.15)
				)
				(justify left bottom)
				(hide yes)
			)
		)
		(property "License" "Apache-2.0"
			(at 191.77 167.64 0)
			(effects
				(font
					(size 1.27 1.27)
					(thickness 0.15)
				)
				(justify left bottom)
				(hide yes)
			)
		)
		(property "Author" "Antmicro"
			(at 194.31 167.64 0)
			(effects
				(font
					(size 1.27 1.27)
					(thickness 0.15)
				)
				(justify left bottom)
				(hide yes)
			)
		)
		(property "Val" "10k"
			(at 167.64 186.69 90)
			(effects
				(font
					(size 1.27 1.27)
					(thickness 0.15)
				)
				(justify right)
			)
		)
		(property "Tolerance" "1%"
			(at 176.53 167.64 0)
			(effects
				(font
					(size 1.27 1.27)
				)
				(justify left bottom)
				(hide yes)
			)
		)
		(pin "2"
		)
		(pin "1"
		)
		(instances
			(project "jetson-agx-thor-baseboard"
				(path ""
					(reference "R289")
					(unit 1)
				)
			)
		)
	)
	(symbol
		(lib_id "antmicroCapacitorsmisc:C_22u_25V_0805")
		(at 229.87 38.1 90)
		(unit 1)
		(exclude_from_sim no)
		(in_bom yes)
		(on_board yes)
		(dnp no)
		(property "Reference" "C26"
			(at 231.775 33.0201 90)
			(effects
				(font
					(size 1.27 1.27)
					(thickness 0.15)
				)
				(justify right)
			)
		)
		(property "Value" "C_22u_25V_0805"
			(at 240.03 17.78 0)
			(effects
				(font
					(size 1.27 1.27)
					(thickness 0.15)
				)
				(justify left bottom)
				(hide yes)
			)
		)
		(property "Footprint" "antmicro-footprints:C_0805_2012Metric"
			(at 242.57 17.78 0)
			(effects
				(font
					(size 1.27 1.27)
					(thickness 0.15)
				)
				(justify left bottom)
				(hide yes)
			)
		)
		(property "Datasheet" "https://product.samsungsem.com/mlcc/CL21A226MAYNNN.do"
			(at 245.11 17.78 0)
			(effects
				(font
					(size 1.27 1.27)
					(thickness 0.15)
				)
				(justify left bottom)
				(hide yes)
			)
		)
		(property "Description" "SMT Multilayer Ceramic Capacitor, 22uF, +/-20%, 25V, X5R, 0805 [2012 Metric]"
			(at 229.87 38.1 0)
			(effects
				(font
					(size 1.27 1.27)
				)
				(hide yes)
			)
		)
		(property "MPN" "CL21A226MAYNNNE"
			(at 247.65 17.78 0)
			(effects
				(font
					(size 1.27 1.27)
					(thickness 0.15)
				)
				(justify left bottom)
				(hide yes)
			)
		)
		(property "Manufacturer" "Samsung Electro-Mechanics"
			(at 250.19 17.78 0)
			(effects
				(font
					(size 1.27 1.27)
					(thickness 0.15)
				)
				(justify left bottom)
				(hide yes)
			)
		)
		(property "License" "Apache-2.0"
			(at 252.73 17.78 0)
			(effects
				(font
					(size 1.27 1.27)
					(thickness 0.15)
				)
				(justify left bottom)
				(hide yes)
			)
		)
		(property "Author" "Antmicro"
			(at 255.27 17.78 0)
			(effects
				(font
					(size 1.27 1.27)
					(thickness 0.15)
				)
				(justify left bottom)
				(hide yes)
			)
		)
		(property "Val" "22u"
			(at 231.775 35.5601 90)
			(effects
				(font
					(size 1.27 1.27)
					(thickness 0.15)
				)
				(justify right)
			)
		)
		(property "Voltage" "25V"
			(at 231.775 38.1 90)
			(effects
				(font
					(size 1.27 1.27)
				)
				(justify right)
			)
		)
		(property "Dielectric" "X5R"
			(at 260.35 17.78 0)
			(effects
				(font
					(size 1.27 1.27)
				)
				(justify left bottom)
				(hide yes)
			)
		)
		(property "Public" "False"
			(at 262.89 17.78 0)
			(effects
				(font
					(size 1.27 1.27)
				)
				(justify left bottom)
				(hide yes)
			)
		)
		(pin "1"
		)
		(pin "2"
		)
		(instances
			(project "jetson-agx-thor-baseboard"
				(path ""
					(reference "C26")
					(unit 1)
				)
			)
		)
	)
	(symbol
		(lib_id "antmicroCapacitors0402:C_100n_0402")
		(at 95.25 240.03 270)
		(mirror x)
		(unit 1)
		(exclude_from_sim no)
		(in_bom yes)
		(on_board yes)
		(dnp no)
		(property "Reference" "C225"
			(at 92.71 236.2136 90)
			(effects
				(font
					(size 1.27 1.27)
					(thickness 0.15)
				)
				(justify right)
			)
		)
		(property "Value" "C_100n_0402"
			(at 85.09 219.71 0)
			(effects
				(font
					(size 1.27 1.27)
					(thickness 0.15)
				)
				(justify left bottom)
				(hide yes)
			)
		)
		(property "Footprint" "antmicro-footprints:C_0402_1005Metric"
			(at 82.55 219.71 0)
			(effects
				(font
					(size 1.27 1.27)
					(thickness 0.15)
				)
				(justify left bottom)
				(hide yes)
			)
		)
		(property "Datasheet" "https://www.murata.com/products/productdetail?partno=GRM155R61H104KE14%23"
			(at 80.01 219.71 0)
			(effects
				(font
					(size 1.27 1.27)
					(thickness 0.15)
				)
				(justify left bottom)
				(hide yes)
			)
		)
		(property "Description" "SMD Multilayer Ceramic Capacitor, 0.1 µF, 50 V, 0402 [1005 Metric], ± 10%, X5R, GRM Series"
			(at 95.25 240.03 0)
			(effects
				(font
					(size 1.27 1.27)
				)
				(hide yes)
			)
		)
		(property "MPN" "GRM155R61H104KE14D"
			(at 77.47 219.71 0)
			(effects
				(font
					(size 1.27 1.27)
					(thickness 0.15)
				)
				(justify left bottom)
				(hide yes)
			)
		)
		(property "Manufacturer" "Murata"
			(at 74.93 219.71 0)
			(effects
				(font
					(size 1.27 1.27)
					(thickness 0.15)
				)
				(justify left bottom)
				(hide yes)
			)
		)
		(property "License" "Apache-2.0"
			(at 72.39 219.71 0)
			(effects
				(font
					(size 1.27 1.27)
					(thickness 0.15)
				)
				(justify left bottom)
				(hide yes)
			)
		)
		(property "Author" "Antmicro"
			(at 69.85 219.71 0)
			(effects
				(font
					(size 1.27 1.27)
					(thickness 0.15)
				)
				(justify left bottom)
				(hide yes)
			)
		)
		(property "Val" "100n"
			(at 92.71 238.7536 90)
			(effects
				(font
					(size 1.27 1.27)
					(thickness 0.15)
				)
				(justify right)
			)
		)
		(property "Voltage" "50V"
			(at 67.31 219.71 0)
			(effects
				(font
					(size 1.27 1.27)
				)
				(justify left bottom)
				(hide yes)
			)
		)
		(property "Dielectric" "X5R"
			(at 64.77 219.71 0)
			(effects
				(font
					(size 1.27 1.27)
				)
				(justify left bottom)
				(hide yes)
			)
		)
		(property "Public" "False"
			(at 62.23 219.71 0)
			(effects
				(font
					(size 1.27 1.27)
				)
				(justify left bottom)
				(hide yes)
			)
		)
		(pin "1"
		)
		(pin "2"
		)
		(instances
			(project "jetson-agx-thor-baseboard"
				(path ""
					(reference "C225")
					(unit 1)
				)
			)
		)
	)
	(symbol
		(lib_id "antmicroPushbuttonSwitches:SW_KMR211NGLFS_SMD")
		(at 356.87 77.47 90)
		(mirror x)
		(unit 1)
		(exclude_from_sim no)
		(in_bom yes)
		(on_board yes)
		(dnp no)
		(property "Reference" "S6"
			(at 353.06 81.28 90)
			(effects
				(font
					(size 1.27 1.27)
				)
				(justify left)
			)
		)
		(property "Value" "SW_KMR211NGLFS_SMD"
			(at 364.49 102.87 0)
			(effects
				(font
					(size 1.27 1.27)
					(thickness 0.15)
				)
				(justify left bottom)
				(hide yes)
			)
		)
		(property "Footprint" "antmicro-footprints:SW_KMR211NGLFS_SMD"
			(at 367.03 102.87 0)
			(effects
				(font
					(size 1.27 1.27)
					(thickness 0.15)
				)
				(justify left bottom)
				(hide yes)
			)
		)
		(property "Datasheet" "http://www.farnell.com/datasheets/2631211.pdf"
			(at 369.57 102.87 0)
			(effects
				(font
					(size 1.27 1.27)
					(thickness 0.15)
				)
				(justify left bottom)
				(hide yes)
			)
		)
		(property "Description" "Tactile Switch, KMR 2 Series, Top Actuated, Surface Mount, Oval Button, 120 gf, 50mA at 32VDC"
			(at 356.87 77.47 0)
			(effects
				(font
					(size 1.27 1.27)
				)
				(hide yes)
			)
		)
		(property "MPN" "KMR211NGLFS"
			(at 353.06 83.82 90)
			(effects
				(font
					(size 1.27 1.27)
					(thickness 0.15)
				)
				(justify left)
			)
		)
		(property "Manufacturer" "C&K"
			(at 372.11 102.87 0)
			(effects
				(font
					(size 1.27 1.27)
					(thickness 0.15)
				)
				(justify left bottom)
				(hide yes)
			)
		)
		(property "Author" "Antmicro"
			(at 374.65 102.87 0)
			(effects
				(font
					(size 1.27 1.27)
					(thickness 0.15)
				)
				(justify left bottom)
				(hide yes)
			)
		)
		(property "License" "Apache-2.0"
			(at 377.19 102.87 0)
			(effects
				(font
					(size 1.27 1.27)
					(thickness 0.15)
				)
				(justify left bottom)
				(hide yes)
			)
		)
		(pin "1"
		)
		(pin "2"
		)
		(pin "3"
		)
		(pin "4"
		)
		(instances
			(project "jetson-agx-thor-baseboard"
				(path ""
					(reference "S6")
					(unit 1)
				)
			)
		)
	)
	(symbol
		(lib_id "antmicroSlideSwitches:SW_SPDT_PCM12SMTR")
		(at 76.2 246.38 0)
		(mirror y)
		(unit 1)
		(exclude_from_sim no)
		(in_bom yes)
		(on_board yes)
		(dnp no)
		(property "Reference" "SW2"
			(at 69.85 238.76 0)
			(effects
				(font
					(size 1.27 1.27)
				)
			)
		)
		(property "Value" "SW_SPDT_PCM12SMTR"
			(at 69.85 241.3 0)
			(effects
				(font
					(size 1.27 1.27)
					(thickness 0.15)
				)
			)
		)
		(property "Footprint" "antmicro-footprints:PCM12SMTR"
			(at 48.26 256.54 0)
			(effects
				(font
					(size 1.27 1.27)
					(thickness 0.15)
				)
				(justify left bottom)
				(hide yes)
			)
		)
		(property "Datasheet" "https://www.mouser.com/datasheet/2/60/pcm-1841544.pdf"
			(at 48.26 259.08 0)
			(effects
				(font
					(size 1.27 1.27)
					(thickness 0.15)
				)
				(justify left bottom)
				(hide yes)
			)
		)
		(property "Description" "Slide switch"
			(at 76.2 246.38 0)
			(effects
				(font
					(size 1.27 1.27)
				)
				(hide yes)
			)
		)
		(property "Manufacturer" "C&K"
			(at 48.26 261.62 0)
			(effects
				(font
					(size 1.27 1.27)
					(thickness 0.15)
				)
				(justify left bottom)
				(hide yes)
			)
		)
		(property "MPN" "PCM12SMTR"
			(at 48.26 264.16 0)
			(effects
				(font
					(size 1.27 1.27)
					(thickness 0.15)
				)
				(justify left bottom)
				(hide yes)
			)
		)
		(property "Author" "Antmicro"
			(at 48.26 266.7 0)
			(effects
				(font
					(size 1.27 1.27)
					(thickness 0.15)
				)
				(justify left bottom)
				(hide yes)
			)
		)
		(property "License" "Apache-2.0"
			(at 48.26 269.24 0)
			(effects
				(font
					(size 1.27 1.27)
					(thickness 0.15)
				)
				(justify left bottom)
				(hide yes)
			)
		)
		(pin "1"
		)
		(pin "2"
		)
		(pin "3"
		)
		(pin "S1"
		)
		(pin "S2"
		)
		(pin "S3"
		)
		(pin "S4"
		)
		(instances
			(project "jetson-agx-thor-baseboard"
				(path ""
					(reference "SW2")
					(unit 1)
				)
			)
		)
	)
	(symbol
		(lib_id "antmicroTestPoints:TP_0.75mm_SMD")
		(at 262.89 78.74 0)
		(unit 1)
		(exclude_from_sim no)
		(in_bom no)
		(on_board yes)
		(dnp no)
		(fields_autoplaced yes)
		(property "Reference" "TP54"
			(at 267.97 78.74 0)
			(effects
				(font
					(size 1.27 1.27)
					(thickness 0.15)
				)
				(justify left)
			)
		)
		(property "Value" "TP_0.75mm_SMD"
			(at 273.05 82.55 0)
			(effects
				(font
					(size 1.27 1.27)
					(thickness 0.15)
				)
				(justify left bottom)
				(hide yes)
			)
		)
		(property "Footprint" "antmicro-footprints:TP_SMD_0.75mm"
			(at 273.05 85.09 0)
			(effects
				(font
					(size 1.27 1.27)
					(thickness 0.15)
				)
				(justify left bottom)
				(hide yes)
			)
		)
		(property "Datasheet" ""
			(at 280.67 91.44 0)
			(effects
				(font
					(size 1.27 1.27)
					(thickness 0.15)
				)
				(justify left bottom)
				(hide yes)
			)
		)
		(property "Description" "SMT test point"
			(at 262.89 78.74 0)
			(effects
				(font
					(size 1.27 1.27)
				)
				(hide yes)
			)
		)
		(property "MPN" ""
			(at 273.685 90.17 0)
			(effects
				(font
					(size 1.27 1.27)
					(thickness 0.15)
				)
				(justify left bottom)
				(hide yes)
			)
		)
		(property "Manufacturer" ""
			(at 273.685 85.09 0)
			(effects
				(font
					(size 1.27 1.27)
					(thickness 0.15)
				)
				(justify left bottom)
				(hide yes)
			)
		)
		(property "Author" "Antmicro"
			(at 273.05 87.63 0)
			(effects
				(font
					(size 1.27 1.27)
					(thickness 0.15)
				)
				(justify left bottom)
				(hide yes)
			)
		)
		(property "License" "Apache-2.0"
			(at 273.05 90.17 0)
			(effects
				(font
					(size 1.27 1.27)
					(thickness 0.15)
				)
				(justify left bottom)
				(hide yes)
			)
		)
		(pin "1"
		)
		(instances
			(project "jetson-agx-thor-baseboard"
				(path ""
					(reference "TP54")
					(unit 1)
				)
			)
		)
	)
	(symbol
		(lib_id "antmicroTestPoints:TP_0.75mm_SMD")
		(at 251.46 113.03 0)
		(unit 1)
		(exclude_from_sim no)
		(in_bom no)
		(on_board yes)
		(dnp no)
		(fields_autoplaced yes)
		(property "Reference" "TP58"
			(at 256.54 113.03 0)
			(effects
				(font
					(size 1.27 1.27)
					(thickness 0.15)
				)
				(justify left)
			)
		)
		(property "Value" "TP_0.75mm_SMD"
			(at 261.62 116.84 0)
			(effects
				(font
					(size 1.27 1.27)
					(thickness 0.15)
				)
				(justify left bottom)
				(hide yes)
			)
		)
		(property "Footprint" "antmicro-footprints:TP_SMD_0.75mm"
			(at 261.62 119.38 0)
			(effects
				(font
					(size 1.27 1.27)
					(thickness 0.15)
				)
				(justify left bottom)
				(hide yes)
			)
		)
		(property "Datasheet" ""
			(at 269.24 125.73 0)
			(effects
				(font
					(size 1.27 1.27)
					(thickness 0.15)
				)
				(justify left bottom)
				(hide yes)
			)
		)
		(property "Description" "SMT test point"
			(at 251.46 113.03 0)
			(effects
				(font
					(size 1.27 1.27)
				)
				(hide yes)
			)
		)
		(property "MPN" ""
			(at 262.255 124.46 0)
			(effects
				(font
					(size 1.27 1.27)
					(thickness 0.15)
				)
				(justify left bottom)
				(hide yes)
			)
		)
		(property "Manufacturer" ""
			(at 262.255 119.38 0)
			(effects
				(font
					(size 1.27 1.27)
					(thickness 0.15)
				)
				(justify left bottom)
				(hide yes)
			)
		)
		(property "Author" "Antmicro"
			(at 261.62 121.92 0)
			(effects
				(font
					(size 1.27 1.27)
					(thickness 0.15)
				)
				(justify left bottom)
				(hide yes)
			)
		)
		(property "License" "Apache-2.0"
			(at 261.62 124.46 0)
			(effects
				(font
					(size 1.27 1.27)
					(thickness 0.15)
				)
				(justify left bottom)
				(hide yes)
			)
		)
		(pin "1"
		)
		(instances
			(project "jetson-agx-thor-baseboard"
				(path ""
					(reference "TP58")
					(unit 1)
				)
			)
		)
	)
	(symbol
		(lib_id "antmicroTestPoints:TP_0.75mm_SMD")
		(at 153.67 190.5 180)
		(unit 1)
		(exclude_from_sim no)
		(in_bom no)
		(on_board yes)
		(dnp no)
		(property "Reference" "TP119"
			(at 149.225 190.5 0)
			(effects
				(font
					(size 1.27 1.27)
					(thickness 0.15)
				)
				(justify left)
			)
		)
		(property "Value" "TP_0.75mm_SMD"
			(at 143.51 186.69 0)
			(effects
				(font
					(size 1.27 1.27)
					(thickness 0.15)
				)
				(justify left bottom)
				(hide yes)
			)
		)
		(property "Footprint" "antmicro-footprints:TP_SMD_0.75mm"
			(at 143.51 184.15 0)
			(effects
				(font
					(size 1.27 1.27)
					(thickness 0.15)
				)
				(justify left bottom)
				(hide yes)
			)
		)
		(property "Datasheet" ""
			(at 135.89 177.8 0)
			(effects
				(font
					(size 1.27 1.27)
					(thickness 0.15)
				)
				(justify left bottom)
				(hide yes)
			)
		)
		(property "Description" "SMT test point"
			(at 153.67 190.5 0)
			(effects
				(font
					(size 1.27 1.27)
				)
				(hide yes)
			)
		)
		(property "MPN" ""
			(at 142.875 179.07 0)
			(effects
				(font
					(size 1.27 1.27)
					(thickness 0.15)
				)
				(justify left bottom)
				(hide yes)
			)
		)
		(property "Manufacturer" ""
			(at 142.875 184.15 0)
			(effects
				(font
					(size 1.27 1.27)
					(thickness 0.15)
				)
				(justify left bottom)
				(hide yes)
			)
		)
		(property "Author" "Antmicro"
			(at 143.51 181.61 0)
			(effects
				(font
					(size 1.27 1.27)
					(thickness 0.15)
				)
				(justify left bottom)
				(hide yes)
			)
		)
		(property "License" "Apache-2.0"
			(at 143.51 179.07 0)
			(effects
				(font
					(size 1.27 1.27)
					(thickness 0.15)
				)
				(justify left bottom)
				(hide yes)
			)
		)
		(pin "1"
		)
		(instances
			(project "jetson-agx-thor-baseboard"
				(path ""
					(reference "TP119")
					(unit 1)
				)
			)
		)
	)
	(symbol
		(lib_id "antmicroCapacitors0603:C_22u_16V_0603")
		(at 106.68 38.1 90)
		(unit 1)
		(exclude_from_sim no)
		(in_bom yes)
		(on_board yes)
		(dnp no)
		(property "Reference" "C19"
			(at 109.22 34.2836 90)
			(effects
				(font
					(size 1.27 1.27)
					(thickness 0.15)
				)
				(justify right)
			)
		)
		(property "Value" "C_22u_16V_0603"
			(at 116.84 17.78 0)
			(effects
				(font
					(size 1.27 1.27)
					(thickness 0.15)
				)
				(justify left bottom)
				(hide yes)
			)
		)
		(property "Footprint" "antmicro-footprints:C_0603_1608Metric_EIA"
			(at 119.38 17.78 0)
			(effects
				(font
					(size 1.27 1.27)
					(thickness 0.15)
				)
				(justify left bottom)
				(hide yes)
			)
		)
		(property "Datasheet" "https://product.samsungsem.com/mlcc/CL10A226MO7JZN.do"
			(at 121.92 17.78 0)
			(effects
				(font
					(size 1.27 1.27)
					(thickness 0.15)
				)
				(justify left bottom)
				(hide yes)
			)
		)
		(property "Description" "SMD Multilayer Ceramic Capacitor"
			(at 106.68 38.1 0)
			(effects
				(font
					(size 1.27 1.27)
				)
				(hide yes)
			)
		)
		(property "MPN" "CL10A226MO7JZNC"
			(at 124.46 17.78 0)
			(effects
				(font
					(size 1.27 1.27)
					(thickness 0.15)
				)
				(justify left bottom)
				(hide yes)
			)
		)
		(property "Manufacturer" "Samsung Electro-Mechanics"
			(at 127 17.78 0)
			(effects
				(font
					(size 1.27 1.27)
					(thickness 0.15)
				)
				(justify left bottom)
				(hide yes)
			)
		)
		(property "License" "Apache-2.0"
			(at 129.54 17.78 0)
			(effects
				(font
					(size 1.27 1.27)
					(thickness 0.15)
				)
				(justify left bottom)
				(hide yes)
			)
		)
		(property "Author" "Antmicro"
			(at 132.08 17.78 0)
			(effects
				(font
					(size 1.27 1.27)
					(thickness 0.15)
				)
				(justify left bottom)
				(hide yes)
			)
		)
		(property "Val" "22u"
			(at 109.22 36.8236 90)
			(effects
				(font
					(size 1.27 1.27)
					(thickness 0.15)
				)
				(justify right)
			)
		)
		(property "Voltage" "16V"
			(at 134.62 17.78 0)
			(effects
				(font
					(size 1.27 1.27)
				)
				(justify left bottom)
				(hide yes)
			)
		)
		(property "Dielectric" "X7R"
			(at 137.16 17.78 0)
			(effects
				(font
					(size 1.27 1.27)
				)
				(justify left bottom)
				(hide yes)
			)
		)
		(property "Public" "False"
			(at 139.7 17.78 0)
			(effects
				(font
					(size 1.27 1.27)
				)
				(justify left bottom)
				(hide yes)
			)
		)
		(pin "1"
		)
		(pin "2"
		)
		(instances
			(project "jetson-agx-thor-baseboard"
				(path ""
					(reference "C19")
					(unit 1)
				)
			)
		)
	)
	(symbol
		(lib_id "antmicroCapacitorsmisc:C_22u_25V_0805")
		(at 220.98 38.1 90)
		(unit 1)
		(exclude_from_sim no)
		(in_bom yes)
		(on_board yes)
		(dnp no)
		(property "Reference" "C27"
			(at 222.885 33.0201 90)
			(effects
				(font
					(size 1.27 1.27)
					(thickness 0.15)
				)
				(justify right)
			)
		)
		(property "Value" "C_22u_25V_0805"
			(at 231.14 17.78 0)
			(effects
				(font
					(size 1.27 1.27)
					(thickness 0.15)
				)
				(justify left bottom)
				(hide yes)
			)
		)
		(property "Footprint" "antmicro-footprints:C_0805_2012Metric"
			(at 233.68 17.78 0)
			(effects
				(font
					(size 1.27 1.27)
					(thickness 0.15)
				)
				(justify left bottom)
				(hide yes)
			)
		)
		(property "Datasheet" "https://product.samsungsem.com/mlcc/CL21A226MAYNNN.do"
			(at 236.22 17.78 0)
			(effects
				(font
					(size 1.27 1.27)
					(thickness 0.15)
				)
				(justify left bottom)
				(hide yes)
			)
		)
		(property "Description" "SMT Multilayer Ceramic Capacitor, 22uF, +/-20%, 25V, X5R, 0805 [2012 Metric]"
			(at 220.98 38.1 0)
			(effects
				(font
					(size 1.27 1.27)
				)
				(hide yes)
			)
		)
		(property "MPN" "CL21A226MAYNNNE"
			(at 238.76 17.78 0)
			(effects
				(font
					(size 1.27 1.27)
					(thickness 0.15)
				)
				(justify left bottom)
				(hide yes)
			)
		)
		(property "Manufacturer" "Samsung Electro-Mechanics"
			(at 241.3 17.78 0)
			(effects
				(font
					(size 1.27 1.27)
					(thickness 0.15)
				)
				(justify left bottom)
				(hide yes)
			)
		)
		(property "License" "Apache-2.0"
			(at 243.84 17.78 0)
			(effects
				(font
					(size 1.27 1.27)
					(thickness 0.15)
				)
				(justify left bottom)
				(hide yes)
			)
		)
		(property "Author" "Antmicro"
			(at 246.38 17.78 0)
			(effects
				(font
					(size 1.27 1.27)
					(thickness 0.15)
				)
				(justify left bottom)
				(hide yes)
			)
		)
		(property "Val" "22u"
			(at 222.885 35.5601 90)
			(effects
				(font
					(size 1.27 1.27)
					(thickness 0.15)
				)
				(justify right)
			)
		)
		(property "Voltage" "25V"
			(at 222.885 38.1 90)
			(effects
				(font
					(size 1.27 1.27)
				)
				(justify right)
			)
		)
		(property "Dielectric" "X5R"
			(at 251.46 17.78 0)
			(effects
				(font
					(size 1.27 1.27)
				)
				(justify left bottom)
				(hide yes)
			)
		)
		(property "Public" "False"
			(at 254 17.78 0)
			(effects
				(font
					(size 1.27 1.27)
				)
				(justify left bottom)
				(hide yes)
			)
		)
		(pin "1"
		)
		(pin "2"
		)
		(instances
			(project "jetson-agx-thor-baseboard"
				(path ""
					(reference "C27")
					(unit 1)
				)
			)
		)
	)
	(symbol
		(lib_id "antmicroTestPoints:TP_0.75mm_SMD")
		(at 194.31 111.76 0)
		(mirror y)
		(unit 1)
		(exclude_from_sim no)
		(in_bom no)
		(on_board yes)
		(dnp no)
		(fields_autoplaced yes)
		(property "Reference" "TP34"
			(at 189.23 111.76 0)
			(effects
				(font
					(size 1.27 1.27)
					(thickness 0.15)
				)
				(justify left)
			)
		)
		(property "Value" "TP_0.75mm_SMD"
			(at 184.15 115.57 0)
			(effects
				(font
					(size 1.27 1.27)
					(thickness 0.15)
				)
				(justify left bottom)
				(hide yes)
			)
		)
		(property "Footprint" "antmicro-footprints:TP_SMD_0.75mm"
			(at 184.15 118.11 0)
			(effects
				(font
					(size 1.27 1.27)
					(thickness 0.15)
				)
				(justify left bottom)
				(hide yes)
			)
		)
		(property "Datasheet" ""
			(at 176.53 124.46 0)
			(effects
				(font
					(size 1.27 1.27)
					(thickness 0.15)
				)
				(justify left bottom)
				(hide yes)
			)
		)
		(property "Description" "SMT test point"
			(at 194.31 111.76 0)
			(effects
				(font
					(size 1.27 1.27)
				)
				(hide yes)
			)
		)
		(property "MPN" ""
			(at 183.515 123.19 0)
			(effects
				(font
					(size 1.27 1.27)
					(thickness 0.15)
				)
				(justify left bottom)
				(hide yes)
			)
		)
		(property "Manufacturer" ""
			(at 183.515 118.11 0)
			(effects
				(font
					(size 1.27 1.27)
					(thickness 0.15)
				)
				(justify left bottom)
				(hide yes)
			)
		)
		(property "Author" "Antmicro"
			(at 184.15 120.65 0)
			(effects
				(font
					(size 1.27 1.27)
					(thickness 0.15)
				)
				(justify left bottom)
				(hide yes)
			)
		)
		(property "License" "Apache-2.0"
			(at 184.15 123.19 0)
			(effects
				(font
					(size 1.27 1.27)
					(thickness 0.15)
				)
				(justify left bottom)
				(hide yes)
			)
		)
		(pin "1"
		)
		(instances
			(project "jetson-agx-thor-baseboard"
				(path ""
					(reference "TP34")
					(unit 1)
				)
			)
		)
	)
	(symbol
		(lib_id "antmicroCapacitors0402:C_100n_0402")
		(at 38.1 160.02 90)
		(unit 1)
		(exclude_from_sim no)
		(in_bom yes)
		(on_board yes)
		(dnp no)
		(fields_autoplaced yes)
		(property "Reference" "C236"
			(at 40.64 156.2036 90)
			(effects
				(font
					(size 1.27 1.27)
					(thickness 0.15)
				)
				(justify right)
			)
		)
		(property "Value" "C_100n_0402"
			(at 48.26 139.7 0)
			(effects
				(font
					(size 1.27 1.27)
					(thickness 0.15)
				)
				(justify left bottom)
				(hide yes)
			)
		)
		(property "Footprint" "antmicro-footprints:C_0402_1005Metric"
			(at 50.8 139.7 0)
			(effects
				(font
					(size 1.27 1.27)
					(thickness 0.15)
				)
				(justify left bottom)
				(hide yes)
			)
		)
		(property "Datasheet" "https://www.murata.com/products/productdetail?partno=GRM155R61H104KE14%23"
			(at 53.34 139.7 0)
			(effects
				(font
					(size 1.27 1.27)
					(thickness 0.15)
				)
				(justify left bottom)
				(hide yes)
			)
		)
		(property "Description" "SMD Multilayer Ceramic Capacitor, 0.1 µF, 50 V, 0402 [1005 Metric], ± 10%, X5R, GRM Series"
			(at 71.12 139.7 0)
			(effects
				(font
					(size 1.27 1.27)
				)
				(justify left bottom)
				(hide yes)
			)
		)
		(property "MPN" "GRM155R61H104KE14D"
			(at 55.88 139.7 0)
			(effects
				(font
					(size 1.27 1.27)
					(thickness 0.15)
				)
				(justify left bottom)
				(hide yes)
			)
		)
		(property "Manufacturer" "Murata"
			(at 58.42 139.7 0)
			(effects
				(font
					(size 1.27 1.27)
					(thickness 0.15)
				)
				(justify left bottom)
				(hide yes)
			)
		)
		(property "License" "Apache-2.0"
			(at 60.96 139.7 0)
			(effects
				(font
					(size 1.27 1.27)
					(thickness 0.15)
				)
				(justify left bottom)
				(hide yes)
			)
		)
		(property "Author" "Antmicro"
			(at 63.5 139.7 0)
			(effects
				(font
					(size 1.27 1.27)
					(thickness 0.15)
				)
				(justify left bottom)
				(hide yes)
			)
		)
		(property "Val" "100n"
			(at 40.64 158.7436 90)
			(effects
				(font
					(size 1.27 1.27)
					(thickness 0.15)
				)
				(justify right)
			)
		)
		(property "Voltage" "50V"
			(at 66.04 139.7 0)
			(effects
				(font
					(size 1.27 1.27)
				)
				(justify left bottom)
				(hide yes)
			)
		)
		(property "Dielectric" "X5R"
			(at 68.58 139.7 0)
			(effects
				(font
					(size 1.27 1.27)
				)
				(justify left bottom)
				(hide yes)
			)
		)
		(pin "1"
		)
		(pin "2"
		)
		(instances
			(project "jetson-agx-thor-baseboard"
				(path ""
					(reference "C236")
					(unit 1)
				)
			)
		)
	)
	(symbol
		(lib_id "antmicroMechanicalParts:Spacer_Drill4.45mm_H4mm_9774040960R")
		(at 378.46 52.07 0)
		(unit 1)
		(exclude_from_sim no)
		(in_bom yes)
		(on_board yes)
		(dnp no)
		(property "Reference" "H7"
			(at 387.35 50.8 0)
			(effects
				(font
					(size 1.27 1.27)
					(thickness 0.15)
				)
				(justify left)
			)
		)
		(property "Value" "Spacer_Drill4.45mm_H4mm_9774040960R"
			(at 387.35 53.34 0)
			(effects
				(font
					(size 1.27 1.27)
					(thickness 0.15)
				)
				(justify left)
				(hide yes)
			)
		)
		(property "Footprint" "antmicro-footprints:Spacer_Drill4.45mm_H4mm_9774040960R"
			(at 401.32 59.69 0)
			(effects
				(font
					(size 1.27 1.27)
					(thickness 0.15)
				)
				(justify left bottom)
				(hide yes)
			)
		)
		(property "Datasheet" "https://www.we-online.com/components/products/datasheet/9774040960R.pdf"
			(at 401.32 62.23 0)
			(effects
				(font
					(size 1.27 1.27)
					(thickness 0.15)
				)
				(justify left bottom)
				(hide yes)
			)
		)
		(property "Description" "Spacer, SMT, Non Stop, Steel, Swage Round, 6 mm x 4 mm, 3.3 mm Internal, WA-SMST Series"
			(at 378.46 52.07 0)
			(effects
				(font
					(size 1.27 1.27)
				)
				(hide yes)
			)
		)
		(property "Manufacturer" "Würth Elektronik"
			(at 401.32 64.77 0)
			(effects
				(font
					(size 1.27 1.27)
					(thickness 0.15)
				)
				(justify left bottom)
				(hide yes)
			)
		)
		(property "MPN" "9774040960R"
			(at 387.35 54.102 0)
			(effects
				(font
					(size 1.27 1.27)
					(thickness 0.15)
				)
				(justify left bottom)
			)
		)
		(property "Author" "Antmicro"
			(at 401.32 69.85 0)
			(effects
				(font
					(size 1.27 1.27)
					(thickness 0.15)
				)
				(justify left bottom)
				(hide yes)
			)
		)
		(property "License" "Apache-2.0"
			(at 401.32 72.39 0)
			(effects
				(font
					(size 1.27 1.27)
					(thickness 0.15)
				)
				(justify left bottom)
				(hide yes)
			)
		)
		(pin "1"
		)
		(instances
			(project "jetson-agx-thor-baseboard"
				(path ""
					(reference "H7")
					(unit 1)
				)
			)
		)
	)
	(symbol
		(lib_id "antmicropower:GND")
		(at 179.07 182.88 0)
		(unit 1)
		(exclude_from_sim no)
		(in_bom yes)
		(on_board yes)
		(dnp no)
		(property "Reference" "#PWR0565"
			(at 187.96 185.42 0)
			(effects
				(font
					(size 1.27 1.27)
					(thickness 0.15)
				)
				(justify left bottom)
				(hide yes)
			)
		)
		(property "Value" "GND"
			(at 179.07 186.69 0)
			(effects
				(font
					(size 1.27 1.27)
					(thickness 0.15)
				)
			)
		)
		(property "Footprint" ""
			(at 187.96 190.5 0)
			(effects
				(font
					(size 1.27 1.27)
					(thickness 0.15)
				)
				(justify left bottom)
				(hide yes)
			)
		)
		(property "Datasheet" ""
			(at 187.96 195.58 0)
			(effects
				(font
					(size 1.27 1.27)
					(thickness 0.15)
				)
				(justify left bottom)
				(hide yes)
			)
		)
		(property "Description" ""
			(at 179.07 182.88 0)
			(effects
				(font
					(size 1.27 1.27)
				)
				(hide yes)
			)
		)
		(property "Author" "Antmicro"
			(at 187.96 190.5 0)
			(effects
				(font
					(size 1.27 1.27)
					(thickness 0.15)
				)
				(justify left bottom)
				(hide yes)
			)
		)
		(property "License" "Apache-2.0"
			(at 187.96 193.04 0)
			(effects
				(font
					(size 1.27 1.27)
					(thickness 0.15)
				)
				(justify left bottom)
				(hide yes)
			)
		)
		(pin "1"
		)
		(instances
			(project "jetson-agx-thor-baseboard"
				(path ""
					(reference "#PWR0565")
					(unit 1)
				)
			)
		)
	)
	(symbol
		(lib_id "antmicroCapacitors0603:C_22u_16V_0603")
		(at 97.79 38.1 90)
		(unit 1)
		(exclude_from_sim no)
		(in_bom yes)
		(on_board yes)
		(dnp no)
		(property "Reference" "C7"
			(at 100.33 34.2836 90)
			(effects
				(font
					(size 1.27 1.27)
					(thickness 0.15)
				)
				(justify right)
			)
		)
		(property "Value" "C_22u_16V_0603"
			(at 107.95 17.78 0)
			(effects
				(font
					(size 1.27 1.27)
					(thickness 0.15)
				)
				(justify left bottom)
				(hide yes)
			)
		)
		(property "Footprint" "antmicro-footprints:C_0603_1608Metric_EIA"
			(at 110.49 17.78 0)
			(effects
				(font
					(size 1.27 1.27)
					(thickness 0.15)
				)
				(justify left bottom)
				(hide yes)
			)
		)
		(property "Datasheet" "https://product.samsungsem.com/mlcc/CL10A226MO7JZN.do"
			(at 113.03 17.78 0)
			(effects
				(font
					(size 1.27 1.27)
					(thickness 0.15)
				)
				(justify left bottom)
				(hide yes)
			)
		)
		(property "Description" "SMD Multilayer Ceramic Capacitor"
			(at 97.79 38.1 0)
			(effects
				(font
					(size 1.27 1.27)
				)
				(hide yes)
			)
		)
		(property "MPN" "CL10A226MO7JZNC"
			(at 115.57 17.78 0)
			(effects
				(font
					(size 1.27 1.27)
					(thickness 0.15)
				)
				(justify left bottom)
				(hide yes)
			)
		)
		(property "Manufacturer" "Samsung Electro-Mechanics"
			(at 118.11 17.78 0)
			(effects
				(font
					(size 1.27 1.27)
					(thickness 0.15)
				)
				(justify left bottom)
				(hide yes)
			)
		)
		(property "License" "Apache-2.0"
			(at 120.65 17.78 0)
			(effects
				(font
					(size 1.27 1.27)
					(thickness 0.15)
				)
				(justify left bottom)
				(hide yes)
			)
		)
		(property "Author" "Antmicro"
			(at 123.19 17.78 0)
			(effects
				(font
					(size 1.27 1.27)
					(thickness 0.15)
				)
				(justify left bottom)
				(hide yes)
			)
		)
		(property "Val" "22u"
			(at 100.33 36.8236 90)
			(effects
				(font
					(size 1.27 1.27)
					(thickness 0.15)
				)
				(justify right)
			)
		)
		(property "Voltage" "16V"
			(at 125.73 17.78 0)
			(effects
				(font
					(size 1.27 1.27)
				)
				(justify left bottom)
				(hide yes)
			)
		)
		(property "Dielectric" "X7R"
			(at 128.27 17.78 0)
			(effects
				(font
					(size 1.27 1.27)
				)
				(justify left bottom)
				(hide yes)
			)
		)
		(property "Public" "False"
			(at 130.81 17.78 0)
			(effects
				(font
					(size 1.27 1.27)
				)
				(justify left bottom)
				(hide yes)
			)
		)
		(pin "1"
		)
		(pin "2"
		)
		(instances
			(project "jetson-agx-thor-baseboard"
				(path ""
					(reference "C7")
					(unit 1)
				)
			)
		)
	)
	(symbol
		(lib_id "antmicroLEDIndicationDiscrete:LED_G_0603_LTST-C190GKT")
		(at 54.61 92.71 270)
		(mirror x)
		(unit 1)
		(exclude_from_sim no)
		(in_bom yes)
		(on_board yes)
		(dnp no)
		(fields_autoplaced yes)
		(property "Reference" "D65"
			(at 52.705 88.9 90)
			(effects
				(font
					(size 1.27 1.27)
				)
				(justify right)
			)
		)
		(property "Value" "LED_G_0603_LTST-C190GKT"
			(at 46.99 69.85 0)
			(effects
				(font
					(size 1.27 1.27)
					(thickness 0.15)
				)
				(justify left bottom)
				(hide yes)
			)
		)
		(property "Footprint" "antmicro-footprints:LED_0603_1608Metric_G"
			(at 44.45 69.85 0)
			(effects
				(font
					(size 1.27 1.27)
					(thickness 0.15)
				)
				(justify left bottom)
				(hide yes)
			)
		)
		(property "Datasheet" "https://media.digikey.com/pdf/Data%20Sheets/Lite-On%20PDFs/LTST-C190GKT.pdf"
			(at 41.91 69.85 0)
			(effects
				(font
					(size 1.27 1.27)
					(thickness 0.15)
				)
				(justify left bottom)
				(hide yes)
			)
		)
		(property "Description" "LED, Green, SMD, 0603, 20 mA, 2.1 V, 569 nm"
			(at 54.61 92.71 0)
			(effects
				(font
					(size 1.27 1.27)
				)
				(hide yes)
			)
		)
		(property "MPN" "LTST-C190GKT"
			(at 39.37 69.85 0)
			(effects
				(font
					(size 1.27 1.27)
					(thickness 0.15)
				)
				(justify left bottom)
				(hide yes)
			)
		)
		(property "Manufacturer" "Lite-On"
			(at 36.83 69.85 0)
			(effects
				(font
					(size 1.27 1.27)
					(thickness 0.15)
				)
				(justify left bottom)
				(hide yes)
			)
		)
		(property "Author" "Antmicro"
			(at 34.29 69.85 0)
			(effects
				(font
					(size 1.27 1.27)
					(thickness 0.15)
				)
				(justify left bottom)
				(hide yes)
			)
		)
		(property "License" "Apache-2.0"
			(at 31.75 69.85 0)
			(effects
				(font
					(size 1.27 1.27)
					(thickness 0.15)
				)
				(justify left bottom)
				(hide yes)
			)
		)
		(property "Color" "Green"
			(at 52.705 91.44 90)
			(effects
				(font
					(size 1.27 1.27)
				)
				(justify right)
			)
		)
		(pin "1"
		)
		(pin "2"
		)
		(instances
			(project "jetson-agx-thor-baseboard"
				(path ""
					(reference "D65")
					(unit 1)
				)
			)
		)
	)
	(symbol
		(lib_id "antmicropower:+5V")
		(at 54.61 80.01 0)
		(mirror y)
		(unit 1)
		(exclude_from_sim no)
		(in_bom yes)
		(on_board yes)
		(dnp no)
		(property "Reference" "#PWR092"
			(at 54.61 83.82 0)
			(effects
				(font
					(size 1.27 1.27)
				)
				(justify left bottom)
				(hide yes)
			)
		)
		(property "Value" "+5V"
			(at 57.15 75.946 0)
			(effects
				(font
					(size 1.27 1.27)
					(thickness 0.15)
				)
				(justify left)
			)
		)
		(property "Footprint" ""
			(at 39.37 87.63 0)
			(effects
				(font
					(size 1.27 1.27)
					(thickness 0.15)
				)
				(justify left bottom)
				(hide yes)
			)
		)
		(property "Datasheet" ""
			(at 39.37 90.17 0)
			(effects
				(font
					(size 1.27 1.27)
					(thickness 0.15)
				)
				(justify left bottom)
				(hide yes)
			)
		)
		(property "Description" ""
			(at 54.61 80.01 0)
			(effects
				(font
					(size 1.27 1.27)
				)
				(hide yes)
			)
		)
		(property "Author" "Antmicro"
			(at 39.37 87.63 0)
			(effects
				(font
					(size 1.27 1.27)
					(thickness 0.15)
				)
				(justify left bottom)
				(hide yes)
			)
		)
		(property "License" "Apache-2.0"
			(at 39.37 90.17 0)
			(effects
				(font
					(size 1.27 1.27)
					(thickness 0.15)
				)
				(justify left bottom)
				(hide yes)
			)
		)
		(pin "1"
		)
		(instances
			(project "jetson-agx-thor-baseboard"
				(path ""
					(reference "#PWR092")
					(unit 1)
				)
			)
		)
	)
	(symbol
		(lib_id "antmicropower:GND")
		(at 78.74 115.57 0)
		(mirror y)
		(unit 1)
		(exclude_from_sim no)
		(in_bom yes)
		(on_board yes)
		(dnp no)
		(property "Reference" "#PWR077"
			(at 78.74 121.92 0)
			(effects
				(font
					(size 1.27 1.27)
				)
				(justify left bottom)
				(hide yes)
			)
		)
		(property "Value" "GND"
			(at 78.74 119.38 0)
			(effects
				(font
					(size 1.27 1.27)
					(thickness 0.15)
				)
			)
		)
		(property "Footprint" ""
			(at 69.85 123.19 0)
			(effects
				(font
					(size 1.27 1.27)
					(thickness 0.15)
				)
				(justify left bottom)
				(hide yes)
			)
		)
		(property "Datasheet" ""
			(at 69.85 128.27 0)
			(effects
				(font
					(size 1.27 1.27)
					(thickness 0.15)
				)
				(justify left bottom)
				(hide yes)
			)
		)
		(property "Description" ""
			(at 78.74 115.57 0)
			(effects
				(font
					(size 1.27 1.27)
				)
				(hide yes)
			)
		)
		(property "Author" "Antmicro"
			(at 69.85 123.19 0)
			(effects
				(font
					(size 1.27 1.27)
					(thickness 0.15)
				)
				(justify left bottom)
				(hide yes)
			)
		)
		(property "License" "Apache-2.0"
			(at 69.85 125.73 0)
			(effects
				(font
					(size 1.27 1.27)
					(thickness 0.15)
				)
				(justify left bottom)
				(hide yes)
			)
		)
		(pin "1"
		)
		(instances
			(project "jetson-agx-thor-baseboard"
				(path ""
					(reference "#PWR077")
					(unit 1)
				)
			)
		)
	)
	(symbol
		(lib_id "antmicropower:GND")
		(at 92.71 259.08 0)
		(mirror y)
		(unit 1)
		(exclude_from_sim no)
		(in_bom yes)
		(on_board yes)
		(dnp no)
		(property "Reference" "#PWR0579"
			(at 83.82 261.62 0)
			(effects
				(font
					(size 1.27 1.27)
					(thickness 0.15)
				)
				(justify left bottom)
				(hide yes)
			)
		)
		(property "Value" "GND"
			(at 92.71 262.89 0)
			(effects
				(font
					(size 1.27 1.27)
					(thickness 0.15)
				)
			)
		)
		(property "Footprint" ""
			(at 83.82 266.7 0)
			(effects
				(font
					(size 1.27 1.27)
					(thickness 0.15)
				)
				(justify left bottom)
				(hide yes)
			)
		)
		(property "Datasheet" ""
			(at 83.82 271.78 0)
			(effects
				(font
					(size 1.27 1.27)
					(thickness 0.15)
				)
				(justify left bottom)
				(hide yes)
			)
		)
		(property "Description" ""
			(at 92.71 259.08 0)
			(effects
				(font
					(size 1.27 1.27)
				)
				(hide yes)
			)
		)
		(property "Author" "Antmicro"
			(at 83.82 266.7 0)
			(effects
				(font
					(size 1.27 1.27)
					(thickness 0.15)
				)
				(justify left bottom)
				(hide yes)
			)
		)
		(property "License" "Apache-2.0"
			(at 83.82 269.24 0)
			(effects
				(font
					(size 1.27 1.27)
					(thickness 0.15)
				)
				(justify left bottom)
				(hide yes)
			)
		)
		(pin "1"
		)
		(instances
			(project "jetson-agx-thor-baseboard"
				(path ""
					(reference "#PWR0579")
					(unit 1)
				)
			)
		)
	)
	(symbol
		(lib_id "antmicroResistors0402:R_470R_0402")
		(at 375.92 208.28 90)
		(unit 1)
		(exclude_from_sim no)
		(in_bom yes)
		(on_board yes)
		(dnp no)
		(property "Reference" "R59"
			(at 376.936 204.47 90)
			(effects
				(font
					(size 1.27 1.27)
					(thickness 0.15)
				)
				(justify right)
			)
		)
		(property "Value" "R_470R_0402"
			(at 388.62 187.96 0)
			(effects
				(font
					(size 1.27 1.27)
					(thickness 0.15)
				)
				(justify left bottom)
				(hide yes)
			)
		)
		(property "Footprint" "antmicro-footprints:R_0402_1005Metric"
			(at 391.16 187.96 0)
			(effects
				(font
					(size 1.27 1.27)
					(thickness 0.15)
				)
				(justify left bottom)
				(hide yes)
			)
		)
		(property "Datasheet" "https://www.bourns.com/docs/product-datasheets/cr.pdf"
			(at 393.7 187.96 0)
			(effects
				(font
					(size 1.27 1.27)
					(thickness 0.15)
				)
				(justify left bottom)
				(hide yes)
			)
		)
		(property "Description" "SMD Chip Resistor, 470 ohm, ± 1%, 62.5 mW, 0402 [1005 Metric], Thick Film, General Purpose"
			(at 375.92 208.28 0)
			(effects
				(font
					(size 1.27 1.27)
				)
				(hide yes)
			)
		)
		(property "MPN" "CR0402-FX-4700GLF"
			(at 396.24 187.96 0)
			(effects
				(font
					(size 1.27 1.27)
					(thickness 0.15)
				)
				(justify left bottom)
				(hide yes)
			)
		)
		(property "Manufacturer" "Bourns"
			(at 398.78 187.96 0)
			(effects
				(font
					(size 1.27 1.27)
					(thickness 0.15)
				)
				(justify left bottom)
				(hide yes)
			)
		)
		(property "License" "Apache-2.0"
			(at 401.32 187.96 0)
			(effects
				(font
					(size 1.27 1.27)
					(thickness 0.15)
				)
				(justify left bottom)
				(hide yes)
			)
		)
		(property "Author" "Antmicro"
			(at 403.86 187.96 0)
			(effects
				(font
					(size 1.27 1.27)
					(thickness 0.15)
				)
				(justify left bottom)
				(hide yes)
			)
		)
		(property "Val" "470R"
			(at 376.936 207.01 90)
			(effects
				(font
					(size 1.27 1.27)
					(thickness 0.15)
				)
				(justify right)
			)
		)
		(property "Tolerance" "1%"
			(at 386.08 187.96 0)
			(effects
				(font
					(size 1.27 1.27)
				)
				(justify left bottom)
				(hide yes)
			)
		)
		(pin "1"
		)
		(pin "2"
		)
		(instances
			(project "jetson-agx-thor-baseboard"
				(path ""
					(reference "R59")
					(unit 1)
				)
			)
		)
	)
	(symbol
		(lib_id "antmicroTransistorsFETsMOSFETsSingle:DMG1012T-7")
		(at 337.82 232.41 0)
		(unit 1)
		(exclude_from_sim no)
		(in_bom yes)
		(on_board yes)
		(dnp no)
		(property "Reference" "Q40"
			(at 348.742 235.712 0)
			(effects
				(font
					(size 1.27 1.27)
					(thickness 0.15)
				)
				(justify right)
			)
		)
		(property "Value" "DMG1012T-7"
			(at 360.68 241.3 0)
			(effects
				(font
					(size 1.27 1.27)
					(thickness 0.15)
				)
				(justify left bottom)
				(hide yes)
			)
		)
		(property "Footprint" "antmicro-footprints:SOT-523"
			(at 360.68 243.84 0)
			(effects
				(font
					(size 1.27 1.27)
					(thickness 0.15)
				)
				(justify left bottom)
				(hide yes)
			)
		)
		(property "Datasheet" "https://www.diodes.com/assets/Datasheets/ds31783.pdf"
			(at 360.68 246.38 0)
			(effects
				(font
					(size 1.27 1.27)
					(thickness 0.15)
				)
				(justify left bottom)
				(hide yes)
			)
		)
		(property "Description" "Power MOSFET, N Channel, 20 V, 630 mA, 0.3 ohm, SOT-523, Surface Mount"
			(at 360.68 259.08 0)
			(effects
				(font
					(size 1.27 1.27)
				)
				(justify left bottom)
				(hide yes)
			)
		)
		(property "MPN" "DMG1012T-7"
			(at 357.378 237.744 0)
			(effects
				(font
					(size 1.27 1.27)
					(thickness 0.15)
				)
				(justify right)
			)
		)
		(property "Manufacturer" "Diodes Incorporated"
			(at 360.68 251.46 0)
			(effects
				(font
					(size 1.27 1.27)
					(thickness 0.15)
				)
				(justify left bottom)
				(hide yes)
			)
		)
		(property "Author" "Antmicro"
			(at 360.68 254 0)
			(effects
				(font
					(size 1.27 1.27)
					(thickness 0.15)
				)
				(justify left bottom)
				(hide yes)
			)
		)
		(property "License" "Apache-2.0"
			(at 360.68 256.54 0)
			(effects
				(font
					(size 1.27 1.27)
					(thickness 0.15)
				)
				(justify left bottom)
				(hide yes)
			)
		)
		(pin "3"
		)
		(pin "1"
		)
		(pin "2"
		)
		(instances
			(project "jetson-agx-thor-baseboard"
				(path ""
					(reference "Q40")
					(unit 1)
				)
			)
		)
	)
	(symbol
		(lib_id "antmicroCapacitors0402:C_100n_0402")
		(at 368.3 85.09 90)
		(unit 1)
		(exclude_from_sim no)
		(in_bom yes)
		(on_board yes)
		(dnp no)
		(fields_autoplaced yes)
		(property "Reference" "C239"
			(at 370.84 81.2736 90)
			(effects
				(font
					(size 1.27 1.27)
					(thickness 0.15)
				)
				(justify right)
			)
		)
		(property "Value" "C_100n_0402"
			(at 391.16 69.85 0)
			(effects
				(font
					(size 1.27 1.27)
					(thickness 0.15)
				)
				(justify left bottom)
				(hide yes)
			)
		)
		(property "Footprint" "antmicro-footprints:C_0402_1005Metric"
			(at 393.7 69.85 0)
			(effects
				(font
					(size 1.27 1.27)
					(thickness 0.15)
				)
				(justify left bottom)
				(hide yes)
			)
		)
		(property "Datasheet" "https://www.murata.com/products/productdetail?partno=GRM155R61H104KE14%23"
			(at 396.24 69.85 0)
			(effects
				(font
					(size 1.27 1.27)
					(thickness 0.15)
				)
				(justify left bottom)
				(hide yes)
			)
		)
		(property "Description" "SMD Multilayer Ceramic Capacitor, 0.1 µF, 50 V, 0402 [1005 Metric], ± 10%, X5R, GRM Series"
			(at 368.3 85.09 0)
			(effects
				(font
					(size 1.27 1.27)
				)
				(hide yes)
			)
		)
		(property "MPN" "GRM155R61H104KE14D"
			(at 398.78 69.85 0)
			(effects
				(font
					(size 1.27 1.27)
					(thickness 0.15)
				)
				(justify left bottom)
				(hide yes)
			)
		)
		(property "Val" "100n"
			(at 370.84 83.8136 90)
			(effects
				(font
					(size 1.27 1.27)
					(thickness 0.15)
				)
				(justify right)
			)
		)
		(property "Voltage" "50V"
			(at 378.46 69.85 0)
			(effects
				(font
					(size 1.27 1.27)
					(thickness 0.15)
				)
				(justify left bottom)
				(hide yes)
			)
		)
		(property "Dielectric" "X5R"
			(at 381 69.85 0)
			(effects
				(font
					(size 1.27 1.27)
					(thickness 0.15)
				)
				(justify left bottom)
				(hide yes)
			)
		)
		(property "Manufacturer" "Murata"
			(at 383.54 69.85 0)
			(effects
				(font
					(size 1.27 1.27)
					(thickness 0.15)
				)
				(justify left bottom)
				(hide yes)
			)
		)
		(property "License" "Apache-2.0"
			(at 386.08 69.85 0)
			(effects
				(font
					(size 1.27 1.27)
					(thickness 0.15)
				)
				(justify left bottom)
				(hide yes)
			)
		)
		(property "Author" "Antmicro"
			(at 388.62 69.85 0)
			(effects
				(font
					(size 1.27 1.27)
					(thickness 0.15)
				)
				(justify left bottom)
				(hide yes)
			)
		)
		(pin "1"
		)
		(pin "2"
		)
		(instances
			(project "jetson-agx-thor-baseboard"
				(path ""
					(reference "C239")
					(unit 1)
				)
			)
		)
	)
	(symbol
		(lib_id "antmicropower:PWR_FLAG")
		(at 179.07 29.21 0)
		(unit 1)
		(exclude_from_sim no)
		(in_bom yes)
		(on_board yes)
		(dnp no)
		(property "Reference" "#FLG022"
			(at 179.07 27.305 0)
			(effects
				(font
					(size 1.27 1.27)
				)
				(hide yes)
			)
		)
		(property "Value" "PWR_FLAG"
			(at 170.688 24.638 0)
			(effects
				(font
					(size 1.27 1.27)
				)
				(justify left)
			)
		)
		(property "Footprint" ""
			(at 179.07 29.21 0)
			(effects
				(font
					(size 1.27 1.27)
				)
				(hide yes)
			)
		)
		(property "Datasheet" ""
			(at 179.07 29.21 0)
			(effects
				(font
					(size 1.27 1.27)
				)
				(hide yes)
			)
		)
		(property "Description" ""
			(at 179.07 29.21 0)
			(effects
				(font
					(size 1.27 1.27)
				)
				(hide yes)
			)
		)
		(pin "1"
		)
		(instances
			(project "jetson-agx-thor-baseboard"
				(path ""
					(reference "#FLG022")
					(unit 1)
				)
			)
		)
	)
	(symbol
		(lib_id "antmicroResistors0402:R_0R_0402")
		(at 209.55 187.96 0)
		(unit 1)
		(exclude_from_sim no)
		(in_bom yes)
		(on_board yes)
		(dnp no)
		(property "Reference" "R301"
			(at 207.645 186.69 0)
			(effects
				(font
					(size 1.27 1.27)
					(thickness 0.15)
				)
			)
		)
		(property "Value" "R_0R_0402"
			(at 229.87 200.66 0)
			(effects
				(font
					(size 1.27 1.27)
					(thickness 0.15)
				)
				(justify left bottom)
				(hide yes)
			)
		)
		(property "Footprint" "antmicro-footprints:R_0402_1005Metric"
			(at 229.87 203.2 0)
			(effects
				(font
					(size 1.27 1.27)
					(thickness 0.15)
				)
				(justify left bottom)
				(hide yes)
			)
		)
		(property "Datasheet" "https://industrial.panasonic.com/cdbs/www-data/pdf/RDA0000/AOA0000C301.pdf"
			(at 229.87 205.74 0)
			(effects
				(font
					(size 1.27 1.27)
					(thickness 0.15)
				)
				(justify left bottom)
				(hide yes)
			)
		)
		(property "Description" "SMD Chip Resistor, Jumper, 0 ohm, 100 mW, 0402 [1005 Metric], Thick Film, General Purpose"
			(at 209.55 187.96 0)
			(effects
				(font
					(size 1.27 1.27)
				)
				(hide yes)
			)
		)
		(property "MPN" "ERJ2GE0R00X"
			(at 229.87 208.28 0)
			(effects
				(font
					(size 1.27 1.27)
					(thickness 0.15)
				)
				(justify left bottom)
				(hide yes)
			)
		)
		(property "Manufacturer" "Panasonic"
			(at 229.87 210.82 0)
			(effects
				(font
					(size 1.27 1.27)
					(thickness 0.15)
				)
				(justify left bottom)
				(hide yes)
			)
		)
		(property "License" "Apache-2.0"
			(at 229.87 213.36 0)
			(effects
				(font
					(size 1.27 1.27)
					(thickness 0.15)
				)
				(justify left bottom)
				(hide yes)
			)
		)
		(property "Author" "Antmicro"
			(at 229.87 215.9 0)
			(effects
				(font
					(size 1.27 1.27)
					(thickness 0.15)
				)
				(justify left bottom)
				(hide yes)
			)
		)
		(property "Val" "0R"
			(at 215.9 186.69 0)
			(effects
				(font
					(size 1.27 1.27)
					(thickness 0.15)
				)
			)
		)
		(property "Tolerance" "~"
			(at 229.87 198.12 0)
			(effects
				(font
					(size 1.27 1.27)
				)
				(justify left bottom)
				(hide yes)
			)
		)
		(property "Current" "1A"
			(at 229.87 218.44 0)
			(effects
				(font
					(size 1.27 1.27)
					(thickness 0.15)
				)
				(justify left bottom)
				(hide yes)
			)
		)
		(pin "2"
		)
		(pin "1"
		)
		(instances
			(project "jetson-agx-thor-baseboard"
				(path ""
					(reference "R301")
					(unit 1)
				)
			)
		)
	)
	(symbol
		(lib_id "antmicropower:+3V3_AON")
		(at 213.36 233.68 0)
		(unit 1)
		(exclude_from_sim no)
		(in_bom yes)
		(on_board yes)
		(dnp no)
		(property "Reference" "#PWR0155"
			(at 213.36 237.49 0)
			(effects
				(font
					(size 1.27 1.27)
				)
				(hide yes)
			)
		)
		(property "Value" "+1V8"
			(at 213.36 229.87 0)
			(effects
				(font
					(size 1.27 1.27)
				)
			)
		)
		(property "Footprint" ""
			(at 213.36 233.68 0)
			(effects
				(font
					(size 1.27 1.27)
				)
				(hide yes)
			)
		)
		(property "Datasheet" ""
			(at 213.36 233.68 0)
			(effects
				(font
					(size 1.27 1.27)
				)
				(hide yes)
			)
		)
		(property "Description" ""
			(at 213.36 233.68 0)
			(effects
				(font
					(size 1.27 1.27)
				)
				(hide yes)
			)
		)
		(pin "1"
		)
		(instances
			(project "jetson-agx-thor-baseboard"
				(path ""
					(reference "#PWR0155")
					(unit 1)
				)
			)
		)
	)
	(symbol
		(lib_id "antmicroTestPoints:TP_0.75mm_SMD")
		(at 251.46 110.49 0)
		(unit 1)
		(exclude_from_sim no)
		(in_bom no)
		(on_board yes)
		(dnp no)
		(fields_autoplaced yes)
		(property "Reference" "TP57"
			(at 256.54 110.49 0)
			(effects
				(font
					(size 1.27 1.27)
					(thickness 0.15)
				)
				(justify left)
			)
		)
		(property "Value" "TP_0.75mm_SMD"
			(at 261.62 114.3 0)
			(effects
				(font
					(size 1.27 1.27)
					(thickness 0.15)
				)
				(justify left bottom)
				(hide yes)
			)
		)
		(property "Footprint" "antmicro-footprints:TP_SMD_0.75mm"
			(at 261.62 116.84 0)
			(effects
				(font
					(size 1.27 1.27)
					(thickness 0.15)
				)
				(justify left bottom)
				(hide yes)
			)
		)
		(property "Datasheet" ""
			(at 269.24 123.19 0)
			(effects
				(font
					(size 1.27 1.27)
					(thickness 0.15)
				)
				(justify left bottom)
				(hide yes)
			)
		)
		(property "Description" "SMT test point"
			(at 251.46 110.49 0)
			(effects
				(font
					(size 1.27 1.27)
				)
				(hide yes)
			)
		)
		(property "MPN" ""
			(at 262.255 121.92 0)
			(effects
				(font
					(size 1.27 1.27)
					(thickness 0.15)
				)
				(justify left bottom)
				(hide yes)
			)
		)
		(property "Manufacturer" ""
			(at 262.255 116.84 0)
			(effects
				(font
					(size 1.27 1.27)
					(thickness 0.15)
				)
				(justify left bottom)
				(hide yes)
			)
		)
		(property "Author" "Antmicro"
			(at 261.62 119.38 0)
			(effects
				(font
					(size 1.27 1.27)
					(thickness 0.15)
				)
				(justify left bottom)
				(hide yes)
			)
		)
		(property "License" "Apache-2.0"
			(at 261.62 121.92 0)
			(effects
				(font
					(size 1.27 1.27)
					(thickness 0.15)
				)
				(justify left bottom)
				(hide yes)
			)
		)
		(pin "1"
		)
		(instances
			(project "jetson-agx-thor-baseboard"
				(path ""
					(reference "TP57")
					(unit 1)
				)
			)
		)
	)
	(symbol
		(lib_id "antmicropower:GND")
		(at 229.87 40.64 0)
		(unit 1)
		(exclude_from_sim no)
		(in_bom yes)
		(on_board yes)
		(dnp no)
		(fields_autoplaced yes)
		(property "Reference" "#PWR039"
			(at 238.76 43.18 0)
			(effects
				(font
					(size 1.27 1.27)
					(thickness 0.15)
				)
				(justify left bottom)
				(hide yes)
			)
		)
		(property "Value" "GND"
			(at 229.87 45.72 0)
			(effects
				(font
					(size 1.27 1.27)
					(thickness 0.15)
				)
			)
		)
		(property "Footprint" ""
			(at 238.76 48.26 0)
			(effects
				(font
					(size 1.27 1.27)
					(thickness 0.15)
				)
				(justify left bottom)
				(hide yes)
			)
		)
		(property "Datasheet" ""
			(at 238.76 53.34 0)
			(effects
				(font
					(size 1.27 1.27)
					(thickness 0.15)
				)
				(justify left bottom)
				(hide yes)
			)
		)
		(property "Description" ""
			(at 229.87 40.64 0)
			(effects
				(font
					(size 1.27 1.27)
				)
				(hide yes)
			)
		)
		(property "Author" "Antmicro"
			(at 238.76 48.26 0)
			(effects
				(font
					(size 1.27 1.27)
					(thickness 0.15)
				)
				(justify left bottom)
				(hide yes)
			)
		)
		(property "License" "Apache-2.0"
			(at 238.76 50.8 0)
			(effects
				(font
					(size 1.27 1.27)
					(thickness 0.15)
				)
				(justify left bottom)
				(hide yes)
			)
		)
		(pin "1"
		)
		(instances
			(project "jetson-agx-thor-baseboard"
				(path ""
					(reference "#PWR039")
					(unit 1)
				)
			)
		)
	)
	(symbol
		(lib_id "antmicropower:GND")
		(at 60.96 170.18 0)
		(unit 1)
		(exclude_from_sim no)
		(in_bom yes)
		(on_board yes)
		(dnp no)
		(property "Reference" "#PWR0539"
			(at 60.96 176.53 0)
			(effects
				(font
					(size 1.27 1.27)
				)
				(justify left bottom)
				(hide yes)
			)
		)
		(property "Value" "GND"
			(at 60.96 173.99 0)
			(effects
				(font
					(size 1.27 1.27)
					(thickness 0.15)
				)
			)
		)
		(property "Footprint" ""
			(at 69.85 177.8 0)
			(effects
				(font
					(size 1.27 1.27)
					(thickness 0.15)
				)
				(justify left bottom)
				(hide yes)
			)
		)
		(property "Datasheet" ""
			(at 69.85 182.88 0)
			(effects
				(font
					(size 1.27 1.27)
					(thickness 0.15)
				)
				(justify left bottom)
				(hide yes)
			)
		)
		(property "Description" ""
			(at 60.96 170.18 0)
			(effects
				(font
					(size 1.27 1.27)
				)
				(hide yes)
			)
		)
		(property "Author" "Antmicro"
			(at 69.85 177.8 0)
			(effects
				(font
					(size 1.27 1.27)
					(thickness 0.15)
				)
				(justify left bottom)
				(hide yes)
			)
		)
		(property "License" "Apache-2.0"
			(at 69.85 180.34 0)
			(effects
				(font
					(size 1.27 1.27)
					(thickness 0.15)
				)
				(justify left bottom)
				(hide yes)
			)
		)
		(pin "1"
		)
		(instances
			(project "jetson-agx-thor-baseboard"
				(path ""
					(reference "#PWR0539")
					(unit 1)
				)
			)
		)
	)
	(symbol
		(lib_id "antmicropower:+3V3_AON")
		(at 344.17 210.82 0)
		(unit 1)
		(exclude_from_sim no)
		(in_bom yes)
		(on_board yes)
		(dnp no)
		(property "Reference" "#PWR0768"
			(at 344.17 214.63 0)
			(effects
				(font
					(size 1.27 1.27)
				)
				(hide yes)
			)
		)
		(property "Value" "+3V3_AON"
			(at 344.17 206.756 0)
			(effects
				(font
					(size 1.27 1.27)
				)
			)
		)
		(property "Footprint" ""
			(at 344.17 210.82 0)
			(effects
				(font
					(size 1.27 1.27)
				)
				(hide yes)
			)
		)
		(property "Datasheet" ""
			(at 344.17 210.82 0)
			(effects
				(font
					(size 1.27 1.27)
				)
				(hide yes)
			)
		)
		(property "Description" ""
			(at 344.17 210.82 0)
			(effects
				(font
					(size 1.27 1.27)
				)
				(hide yes)
			)
		)
		(pin "1"
		)
		(instances
			(project "jetson-agx-thor-baseboard"
				(path ""
					(reference "#PWR0768")
					(unit 1)
				)
			)
		)
	)
	(symbol
		(lib_id "antmicroCapacitors0603:C_22u_16V_0603")
		(at 142.24 38.1 90)
		(unit 1)
		(exclude_from_sim no)
		(in_bom yes)
		(on_board yes)
		(dnp no)
		(property "Reference" "C23"
			(at 144.78 34.2836 90)
			(effects
				(font
					(size 1.27 1.27)
					(thickness 0.15)
				)
				(justify right)
			)
		)
		(property "Value" "C_22u_16V_0603"
			(at 152.4 17.78 0)
			(effects
				(font
					(size 1.27 1.27)
					(thickness 0.15)
				)
				(justify left bottom)
				(hide yes)
			)
		)
		(property "Footprint" "antmicro-footprints:C_0603_1608Metric_EIA"
			(at 154.94 17.78 0)
			(effects
				(font
					(size 1.27 1.27)
					(thickness 0.15)
				)
				(justify left bottom)
				(hide yes)
			)
		)
		(property "Datasheet" "https://product.samsungsem.com/mlcc/CL10A226MO7JZN.do"
			(at 157.48 17.78 0)
			(effects
				(font
					(size 1.27 1.27)
					(thickness 0.15)
				)
				(justify left bottom)
				(hide yes)
			)
		)
		(property "Description" "SMD Multilayer Ceramic Capacitor"
			(at 142.24 38.1 0)
			(effects
				(font
					(size 1.27 1.27)
				)
				(hide yes)
			)
		)
		(property "MPN" "CL10A226MO7JZNC"
			(at 160.02 17.78 0)
			(effects
				(font
					(size 1.27 1.27)
					(thickness 0.15)
				)
				(justify left bottom)
				(hide yes)
			)
		)
		(property "Manufacturer" "Samsung Electro-Mechanics"
			(at 162.56 17.78 0)
			(effects
				(font
					(size 1.27 1.27)
					(thickness 0.15)
				)
				(justify left bottom)
				(hide yes)
			)
		)
		(property "License" "Apache-2.0"
			(at 165.1 17.78 0)
			(effects
				(font
					(size 1.27 1.27)
					(thickness 0.15)
				)
				(justify left bottom)
				(hide yes)
			)
		)
		(property "Author" "Antmicro"
			(at 167.64 17.78 0)
			(effects
				(font
					(size 1.27 1.27)
					(thickness 0.15)
				)
				(justify left bottom)
				(hide yes)
			)
		)
		(property "Val" "22u"
			(at 144.78 36.8236 90)
			(effects
				(font
					(size 1.27 1.27)
					(thickness 0.15)
				)
				(justify right)
			)
		)
		(property "Voltage" "16V"
			(at 170.18 17.78 0)
			(effects
				(font
					(size 1.27 1.27)
				)
				(justify left bottom)
				(hide yes)
			)
		)
		(property "Dielectric" "X7R"
			(at 172.72 17.78 0)
			(effects
				(font
					(size 1.27 1.27)
				)
				(justify left bottom)
				(hide yes)
			)
		)
		(property "Public" "False"
			(at 175.26 17.78 0)
			(effects
				(font
					(size 1.27 1.27)
				)
				(justify left bottom)
				(hide yes)
			)
		)
		(pin "1"
		)
		(pin "2"
		)
		(instances
			(project "jetson-agx-thor-baseboard"
				(path ""
					(reference "C23")
					(unit 1)
				)
			)
		)
	)
	(symbol
		(lib_id "antmicroBatteryHoldersClipsContacts:Battery_Holder_MS621FE-FL11E")
		(at 148.59 80.01 0)
		(unit 1)
		(exclude_from_sim no)
		(in_bom yes)
		(on_board yes)
		(dnp no)
		(fields_autoplaced yes)
		(property "Reference" "BT1"
			(at 144.78 83.185 0)
			(effects
				(font
					(size 1.27 1.27)
					(thickness 0.15)
				)
				(justify right)
			)
		)
		(property "Value" "Battery_Holder_MS621FE-FL11E"
			(at 166.37 87.63 0)
			(effects
				(font
					(size 1.27 1.27)
					(thickness 0.15)
				)
				(justify left bottom)
				(hide yes)
			)
		)
		(property "Footprint" "antmicro-footprints:MS621FE-FL11E"
			(at 166.37 90.17 0)
			(effects
				(font
					(size 1.27 1.27)
					(thickness 0.15)
				)
				(justify left bottom)
				(hide yes)
			)
		)
		(property "Datasheet" "https://www.sii.co.jp/en/me/datasheets/ms-rechargeable/ms621fe/"
			(at 166.37 92.71 0)
			(effects
				(font
					(size 1.27 1.27)
					(thickness 0.15)
				)
				(justify left bottom)
				(hide yes)
			)
		)
		(property "Description" "Rechargeable Battery, Coin Cell, Single Cell, 3 V, Lithium Manganese Dioxide, 5.5 mAh, Button Cell"
			(at 148.59 80.01 0)
			(effects
				(font
					(size 1.27 1.27)
				)
				(hide yes)
			)
		)
		(property "Manufacturer" "Seiko Instruments"
			(at 166.37 95.25 0)
			(effects
				(font
					(size 1.27 1.27)
					(thickness 0.15)
				)
				(justify left bottom)
				(hide yes)
			)
		)
		(property "MPN" "MS621FE-FL11E"
			(at 144.78 85.725 0)
			(effects
				(font
					(size 1.27 1.27)
					(thickness 0.15)
				)
				(justify right)
			)
		)
		(property "Author" "Antmicro"
			(at 166.37 97.79 0)
			(effects
				(font
					(size 1.27 1.27)
					(thickness 0.15)
				)
				(justify left bottom)
				(hide yes)
			)
		)
		(property "License" "Apache-2.0"
			(at 166.37 100.33 0)
			(effects
				(font
					(size 1.27 1.27)
					(thickness 0.15)
				)
				(justify left bottom)
				(hide yes)
			)
		)
		(pin "2"
		)
		(pin "1"
		)
		(instances
			(project "jetson-agx-thor-baseboard"
				(path ""
					(reference "BT1")
					(unit 1)
				)
			)
		)
	)
	(symbol
		(lib_id "antmicropower:+3V3_AON")
		(at 96.52 143.51 0)
		(mirror y)
		(unit 1)
		(exclude_from_sim no)
		(in_bom yes)
		(on_board yes)
		(dnp no)
		(property "Reference" "#PWR0669"
			(at 96.52 147.32 0)
			(effects
				(font
					(size 1.27 1.27)
				)
				(hide yes)
			)
		)
		(property "Value" "+3V3_AON"
			(at 92.964 139.192 0)
			(effects
				(font
					(size 1.27 1.27)
				)
			)
		)
		(property "Footprint" ""
			(at 96.52 143.51 0)
			(effects
				(font
					(size 1.27 1.27)
				)
				(hide yes)
			)
		)
		(property "Datasheet" ""
			(at 96.52 143.51 0)
			(effects
				(font
					(size 1.27 1.27)
				)
				(hide yes)
			)
		)
		(property "Description" ""
			(at 96.52 143.51 0)
			(effects
				(font
					(size 1.27 1.27)
				)
				(hide yes)
			)
		)
		(pin "1"
		)
		(instances
			(project "jetson-agx-thor-baseboard"
				(path ""
					(reference "#PWR0669")
					(unit 1)
				)
			)
		)
	)
	(symbol
		(lib_id "antmicroResistors0402:R_10k_0402")
		(at 96.52 149.86 90)
		(unit 1)
		(exclude_from_sim no)
		(in_bom yes)
		(on_board yes)
		(dnp no)
		(property "Reference" "R14"
			(at 97.79 146.05 90)
			(effects
				(font
					(size 1.27 1.27)
					(thickness 0.15)
				)
				(justify right)
			)
		)
		(property "Value" "R_10k_0402"
			(at 109.22 129.54 0)
			(effects
				(font
					(size 1.27 1.27)
					(thickness 0.15)
				)
				(justify left bottom)
				(hide yes)
			)
		)
		(property "Footprint" "antmicro-footprints:R_0402_1005Metric"
			(at 111.76 129.54 0)
			(effects
				(font
					(size 1.27 1.27)
					(thickness 0.15)
				)
				(justify left bottom)
				(hide yes)
			)
		)
		(property "Datasheet" "https://www.bourns.com/docs/product-datasheets/cr.pdf"
			(at 114.3 129.54 0)
			(effects
				(font
					(size 1.27 1.27)
					(thickness 0.15)
				)
				(justify left bottom)
				(hide yes)
			)
		)
		(property "Description" "SMD Chip Resistor, 10 kohm, ± 1%, 62.5 mW, 0402 [1005 Metric], Thick Film, General Purpose"
			(at 96.52 149.86 0)
			(effects
				(font
					(size 1.27 1.27)
				)
				(hide yes)
			)
		)
		(property "MPN" "CR0402-FX-1002GLF"
			(at 116.84 129.54 0)
			(effects
				(font
					(size 1.27 1.27)
					(thickness 0.15)
				)
				(justify left bottom)
				(hide yes)
			)
		)
		(property "Manufacturer" "Bourns"
			(at 119.38 129.54 0)
			(effects
				(font
					(size 1.27 1.27)
					(thickness 0.15)
				)
				(justify left bottom)
				(hide yes)
			)
		)
		(property "License" "Apache-2.0"
			(at 121.92 129.54 0)
			(effects
				(font
					(size 1.27 1.27)
					(thickness 0.15)
				)
				(justify left bottom)
				(hide yes)
			)
		)
		(property "Author" "Antmicro"
			(at 124.46 129.54 0)
			(effects
				(font
					(size 1.27 1.27)
					(thickness 0.15)
				)
				(justify left bottom)
				(hide yes)
			)
		)
		(property "Val" "10k"
			(at 97.79 148.59 90)
			(effects
				(font
					(size 1.27 1.27)
					(thickness 0.15)
				)
				(justify right)
			)
		)
		(property "Tolerance" "1%"
			(at 106.68 129.54 0)
			(effects
				(font
					(size 1.27 1.27)
				)
				(justify left bottom)
				(hide yes)
			)
		)
		(pin "1"
		)
		(pin "2"
		)
		(instances
			(project "jetson-agx-thor-baseboard"
				(path ""
					(reference "R14")
					(unit 1)
				)
			)
		)
	)
	(symbol
		(lib_id "antmicropower:GND")
		(at 85.09 115.57 0)
		(mirror y)
		(unit 1)
		(exclude_from_sim no)
		(in_bom yes)
		(on_board yes)
		(dnp no)
		(property "Reference" "#PWR091"
			(at 85.09 121.92 0)
			(effects
				(font
					(size 1.27 1.27)
				)
				(justify left bottom)
				(hide yes)
			)
		)
		(property "Value" "GND"
			(at 85.09 119.38 0)
			(effects
				(font
					(size 1.27 1.27)
					(thickness 0.15)
				)
			)
		)
		(property "Footprint" ""
			(at 76.2 123.19 0)
			(effects
				(font
					(size 1.27 1.27)
					(thickness 0.15)
				)
				(justify left bottom)
				(hide yes)
			)
		)
		(property "Datasheet" ""
			(at 76.2 128.27 0)
			(effects
				(font
					(size 1.27 1.27)
					(thickness 0.15)
				)
				(justify left bottom)
				(hide yes)
			)
		)
		(property "Description" ""
			(at 85.09 115.57 0)
			(effects
				(font
					(size 1.27 1.27)
				)
				(hide yes)
			)
		)
		(property "Author" "Antmicro"
			(at 76.2 123.19 0)
			(effects
				(font
					(size 1.27 1.27)
					(thickness 0.15)
				)
				(justify left bottom)
				(hide yes)
			)
		)
		(property "License" "Apache-2.0"
			(at 76.2 125.73 0)
			(effects
				(font
					(size 1.27 1.27)
					(thickness 0.15)
				)
				(justify left bottom)
				(hide yes)
			)
		)
		(pin "1"
		)
		(instances
			(project "jetson-agx-thor-baseboard"
				(path ""
					(reference "#PWR091")
					(unit 1)
				)
			)
		)
	)
	(symbol
		(lib_id "antmicroCapacitors0402:C_1u_25V_0402")
		(at 212.09 38.1 90)
		(unit 1)
		(exclude_from_sim no)
		(in_bom yes)
		(on_board yes)
		(dnp no)
		(property "Reference" "C366"
			(at 213.995 33.02 90)
			(effects
				(font
					(size 1.27 1.27)
					(thickness 0.15)
				)
				(justify right)
			)
		)
		(property "Value" "C_1u_25V_0402"
			(at 222.25 17.78 0)
			(effects
				(font
					(size 1.27 1.27)
					(thickness 0.15)
				)
				(justify left bottom)
				(hide yes)
			)
		)
		(property "Footprint" "antmicro-footprints:C_0402_1005Metric"
			(at 224.79 17.78 0)
			(effects
				(font
					(size 1.27 1.27)
					(thickness 0.15)
				)
				(justify left bottom)
				(hide yes)
			)
		)
		(property "Datasheet" "https://www.murata.com/products/productdetail?partno=GRM155R61E105KE11%23"
			(at 227.33 17.78 0)
			(effects
				(font
					(size 1.27 1.27)
					(thickness 0.15)
				)
				(justify left bottom)
				(hide yes)
			)
		)
		(property "Description" "SMD Multilayer Ceramic Capacitor, 1 µF, 25 V, 0402 [1005 Metric], ± 10%, X5R, GRM Series"
			(at 245.11 17.78 0)
			(effects
				(font
					(size 1.27 1.27)
				)
				(justify left bottom)
				(hide yes)
			)
		)
		(property "MPN" "GRM155R61E105KE11J"
			(at 229.87 17.78 0)
			(effects
				(font
					(size 1.27 1.27)
					(thickness 0.15)
				)
				(justify left bottom)
				(hide yes)
			)
		)
		(property "Manufacturer" "Murata"
			(at 232.41 17.78 0)
			(effects
				(font
					(size 1.27 1.27)
					(thickness 0.15)
				)
				(justify left bottom)
				(hide yes)
			)
		)
		(property "License" "Apache-2.0"
			(at 234.95 17.78 0)
			(effects
				(font
					(size 1.27 1.27)
					(thickness 0.15)
				)
				(justify left bottom)
				(hide yes)
			)
		)
		(property "Author" "Antmicro"
			(at 237.49 17.78 0)
			(effects
				(font
					(size 1.27 1.27)
					(thickness 0.15)
				)
				(justify left bottom)
				(hide yes)
			)
		)
		(property "Val" "1u"
			(at 213.995 35.56 90)
			(effects
				(font
					(size 1.27 1.27)
					(thickness 0.15)
				)
				(justify right)
			)
		)
		(property "Voltage" "25V"
			(at 213.995 38.0999 90)
			(effects
				(font
					(size 1.27 1.27)
				)
				(justify right)
			)
		)
		(property "Dielectric" "X5R"
			(at 242.57 17.78 0)
			(effects
				(font
					(size 1.27 1.27)
				)
				(justify left bottom)
				(hide yes)
			)
		)
		(pin "1"
		)
		(pin "2"
		)
		(instances
			(project "jetson-agx-thor-baseboard"
				(path ""
					(reference "C366")
					(unit 1)
				)
			)
		)
	)
	(symbol
		(lib_id "antmicroPMICPowerSequencers:MAX16150A_SOT")
		(at 187.96 187.96 0)
		(unit 1)
		(exclude_from_sim no)
		(in_bom yes)
		(on_board yes)
		(dnp no)
		(fields_autoplaced yes)
		(property "Reference" "U70"
			(at 196.85 180.34 0)
			(effects
				(font
					(size 1.27 1.27)
					(thickness 0.15)
				)
			)
		)
		(property "Value" "MAX16150A_SOT"
			(at 219.71 194.31 0)
			(effects
				(font
					(size 1.27 1.27)
					(thickness 0.15)
				)
				(justify left bottom)
				(hide yes)
			)
		)
		(property "Footprint" "antmicro-footprints:SOT-23-6"
			(at 219.71 196.85 0)
			(effects
				(font
					(size 1.27 1.27)
					(thickness 0.15)
				)
				(justify left bottom)
				(hide yes)
			)
		)
		(property "Datasheet" "https://datasheets.maximintegrated.com/en/ds/MAX16150.pdf"
			(at 219.71 199.39 0)
			(effects
				(font
					(size 1.27 1.27)
					(thickness 0.15)
				)
				(justify left bottom)
				(hide yes)
			)
		)
		(property "Description" "Pushbutton On/Off Controller, Latched Output, 1.3 to 5.5 V Supply, 50 ms Debounce Time, SOT-23-6"
			(at 187.96 187.96 0)
			(effects
				(font
					(size 1.27 1.27)
				)
				(hide yes)
			)
		)
		(property "Manufacturer" "Maxim Integrated Products"
			(at 219.71 201.93 0)
			(effects
				(font
					(size 1.27 1.27)
					(thickness 0.15)
				)
				(justify left bottom)
				(hide yes)
			)
		)
		(property "MPN" "MAX16150AUT+T"
			(at 196.85 182.88 0)
			(effects
				(font
					(size 1.27 1.27)
					(thickness 0.15)
				)
			)
		)
		(property "License" "Apache-2.0"
			(at 219.71 207.01 0)
			(effects
				(font
					(size 1.27 1.27)
					(thickness 0.15)
				)
				(justify left bottom)
				(hide yes)
			)
		)
		(property "Author" "Antmicro"
			(at 219.71 209.55 0)
			(effects
				(font
					(size 1.27 1.27)
					(thickness 0.15)
				)
				(justify left bottom)
				(hide yes)
			)
		)
		(pin "4"
		)
		(pin "5"
		)
		(pin "2"
		)
		(pin "6"
		)
		(pin "1"
		)
		(pin "3"
		)
		(instances
			(project "jetson-agx-thor-baseboard"
				(path ""
					(reference "U70")
					(unit 1)
				)
			)
		)
	)
	(symbol
		(lib_id "antmicroCapacitors0402:C_1u_25V_0402")
		(at 187.96 38.1 90)
		(unit 1)
		(exclude_from_sim no)
		(in_bom yes)
		(on_board yes)
		(dnp no)
		(property "Reference" "C84"
			(at 189.865 33.02 90)
			(effects
				(font
					(size 1.27 1.27)
					(thickness 0.15)
				)
				(justify right)
			)
		)
		(property "Value" "C_1u_25V_0402"
			(at 198.12 17.78 0)
			(effects
				(font
					(size 1.27 1.27)
					(thickness 0.15)
				)
				(justify left bottom)
				(hide yes)
			)
		)
		(property "Footprint" "antmicro-footprints:C_0402_1005Metric"
			(at 200.66 17.78 0)
			(effects
				(font
					(size 1.27 1.27)
					(thickness 0.15)
				)
				(justify left bottom)
				(hide yes)
			)
		)
		(property "Datasheet" "https://www.murata.com/products/productdetail?partno=GRM155R61E105KE11%23"
			(at 203.2 17.78 0)
			(effects
				(font
					(size 1.27 1.27)
					(thickness 0.15)
				)
				(justify left bottom)
				(hide yes)
			)
		)
		(property "Description" "SMD Multilayer Ceramic Capacitor, 1 µF, 25 V, 0402 [1005 Metric], ± 10%, X5R, GRM Series"
			(at 220.98 17.78 0)
			(effects
				(font
					(size 1.27 1.27)
				)
				(justify left bottom)
				(hide yes)
			)
		)
		(property "MPN" "GRM155R61E105KE11J"
			(at 205.74 17.78 0)
			(effects
				(font
					(size 1.27 1.27)
					(thickness 0.15)
				)
				(justify left bottom)
				(hide yes)
			)
		)
		(property "Manufacturer" "Murata"
			(at 208.28 17.78 0)
			(effects
				(font
					(size 1.27 1.27)
					(thickness 0.15)
				)
				(justify left bottom)
				(hide yes)
			)
		)
		(property "License" "Apache-2.0"
			(at 210.82 17.78 0)
			(effects
				(font
					(size 1.27 1.27)
					(thickness 0.15)
				)
				(justify left bottom)
				(hide yes)
			)
		)
		(property "Author" "Antmicro"
			(at 213.36 17.78 0)
			(effects
				(font
					(size 1.27 1.27)
					(thickness 0.15)
				)
				(justify left bottom)
				(hide yes)
			)
		)
		(property "Val" "1u"
			(at 189.865 35.56 90)
			(effects
				(font
					(size 1.27 1.27)
					(thickness 0.15)
				)
				(justify right)
			)
		)
		(property "Voltage" "25V"
			(at 189.865 38.0999 90)
			(effects
				(font
					(size 1.27 1.27)
				)
				(justify right)
			)
		)
		(property "Dielectric" "X5R"
			(at 218.44 17.78 0)
			(effects
				(font
					(size 1.27 1.27)
				)
				(justify left bottom)
				(hide yes)
			)
		)
		(pin "1"
		)
		(pin "2"
		)
		(instances
			(project ""
				(path ""
					(reference "C84")
					(unit 1)
				)
			)
		)
	)
	(symbol
		(lib_id "antmicroResistors0402:R_10k_0402")
		(at 39.37 38.1 90)
		(unit 1)
		(exclude_from_sim no)
		(in_bom yes)
		(on_board yes)
		(dnp no)
		(property "Reference" "R68"
			(at 40.64 34.29 90)
			(effects
				(font
					(size 1.27 1.27)
					(thickness 0.15)
				)
				(justify right)
			)
		)
		(property "Value" "R_10k_0402"
			(at 52.07 17.78 0)
			(effects
				(font
					(size 1.27 1.27)
					(thickness 0.15)
				)
				(justify left bottom)
				(hide yes)
			)
		)
		(property "Footprint" "antmicro-footprints:R_0402_1005Metric"
			(at 54.61 17.78 0)
			(effects
				(font
					(size 1.27 1.27)
					(thickness 0.15)
				)
				(justify left bottom)
				(hide yes)
			)
		)
		(property "Datasheet" "https://www.bourns.com/docs/product-datasheets/cr.pdf"
			(at 57.15 17.78 0)
			(effects
				(font
					(size 1.27 1.27)
					(thickness 0.15)
				)
				(justify left bottom)
				(hide yes)
			)
		)
		(property "Description" "SMD Chip Resistor, 10 kohm, ± 1%, 62.5 mW, 0402 [1005 Metric], Thick Film, General Purpose"
			(at 39.37 38.1 0)
			(effects
				(font
					(size 1.27 1.27)
				)
				(hide yes)
			)
		)
		(property "MPN" "CR0402-FX-1002GLF"
			(at 59.69 17.78 0)
			(effects
				(font
					(size 1.27 1.27)
					(thickness 0.15)
				)
				(justify left bottom)
				(hide yes)
			)
		)
		(property "Manufacturer" "Bourns"
			(at 62.23 17.78 0)
			(effects
				(font
					(size 1.27 1.27)
					(thickness 0.15)
				)
				(justify left bottom)
				(hide yes)
			)
		)
		(property "License" "Apache-2.0"
			(at 64.77 17.78 0)
			(effects
				(font
					(size 1.27 1.27)
					(thickness 0.15)
				)
				(justify left bottom)
				(hide yes)
			)
		)
		(property "Author" "Antmicro"
			(at 67.31 17.78 0)
			(effects
				(font
					(size 1.27 1.27)
					(thickness 0.15)
				)
				(justify left bottom)
				(hide yes)
			)
		)
		(property "Val" "10k"
			(at 40.64 36.83 90)
			(effects
				(font
					(size 1.27 1.27)
					(thickness 0.15)
				)
				(justify right)
			)
		)
		(property "Tolerance" "1%"
			(at 49.53 17.78 0)
			(effects
				(font
					(size 1.27 1.27)
				)
				(justify left bottom)
				(hide yes)
			)
		)
		(pin "2"
		)
		(pin "1"
		)
		(instances
			(project "jetson-agx-thor-baseboard"
				(path ""
					(reference "R68")
					(unit 1)
				)
			)
		)
	)
	(symbol
		(lib_id "antmicroResistors0402:R_100k_0402")
		(at 344.17 217.17 90)
		(unit 1)
		(exclude_from_sim no)
		(in_bom yes)
		(on_board yes)
		(dnp no)
		(fields_autoplaced yes)
		(property "Reference" "R363"
			(at 346.71 213.36 90)
			(effects
				(font
					(size 1.27 1.27)
					(thickness 0.15)
				)
				(justify right)
			)
		)
		(property "Value" "R_100k_0402"
			(at 356.87 196.85 0)
			(effects
				(font
					(size 1.27 1.27)
					(thickness 0.15)
				)
				(justify left bottom)
				(hide yes)
			)
		)
		(property "Footprint" "antmicro-footprints:R_0402_1005Metric"
			(at 359.41 196.85 0)
			(effects
				(font
					(size 1.27 1.27)
					(thickness 0.15)
				)
				(justify left bottom)
				(hide yes)
			)
		)
		(property "Datasheet" "https://www.bourns.com/docs/product-datasheets/cr.pdf"
			(at 361.95 196.85 0)
			(effects
				(font
					(size 1.27 1.27)
					(thickness 0.15)
				)
				(justify left bottom)
				(hide yes)
			)
		)
		(property "Description" "SMD Chip Resistor, 100 kohm, ± 1%, 62.5 mW, 0402 [1005 Metric], Thick Film, General Purpose"
			(at 374.65 196.85 0)
			(effects
				(font
					(size 1.27 1.27)
				)
				(justify left bottom)
				(hide yes)
			)
		)
		(property "MPN" "CR0402-FX-1003GLF"
			(at 364.49 196.85 0)
			(effects
				(font
					(size 1.27 1.27)
					(thickness 0.15)
				)
				(justify left bottom)
				(hide yes)
			)
		)
		(property "Manufacturer" "Bourns"
			(at 367.03 196.85 0)
			(effects
				(font
					(size 1.27 1.27)
					(thickness 0.15)
				)
				(justify left bottom)
				(hide yes)
			)
		)
		(property "License" "Apache-2.0"
			(at 369.57 196.85 0)
			(effects
				(font
					(size 1.27 1.27)
					(thickness 0.15)
				)
				(justify left bottom)
				(hide yes)
			)
		)
		(property "Author" "Antmicro"
			(at 372.11 196.85 0)
			(effects
				(font
					(size 1.27 1.27)
					(thickness 0.15)
				)
				(justify left bottom)
				(hide yes)
			)
		)
		(property "Val" "100k"
			(at 346.71 215.9 90)
			(effects
				(font
					(size 1.27 1.27)
					(thickness 0.15)
				)
				(justify right)
			)
		)
		(property "Tolerance" "1%"
			(at 354.33 196.85 0)
			(effects
				(font
					(size 1.27 1.27)
				)
				(justify left bottom)
				(hide yes)
			)
		)
		(pin "1"
		)
		(pin "2"
		)
		(instances
			(project "jetson-agx-thor-baseboard"
				(path ""
					(reference "R363")
					(unit 1)
				)
			)
		)
	)
	(symbol
		(lib_id "antmicropower:+5V")
		(at 360.68 201.93 0)
		(unit 1)
		(exclude_from_sim no)
		(in_bom yes)
		(on_board yes)
		(dnp no)
		(property "Reference" "#PWR0124"
			(at 360.68 205.74 0)
			(effects
				(font
					(size 1.27 1.27)
				)
				(justify left bottom)
				(hide yes)
			)
		)
		(property "Value" "+5V"
			(at 358.14 197.866 0)
			(effects
				(font
					(size 1.27 1.27)
					(thickness 0.15)
				)
				(justify left)
			)
		)
		(property "Footprint" ""
			(at 375.92 209.55 0)
			(effects
				(font
					(size 1.27 1.27)
					(thickness 0.15)
				)
				(justify left bottom)
				(hide yes)
			)
		)
		(property "Datasheet" ""
			(at 375.92 212.09 0)
			(effects
				(font
					(size 1.27 1.27)
					(thickness 0.15)
				)
				(justify left bottom)
				(hide yes)
			)
		)
		(property "Description" ""
			(at 360.68 201.93 0)
			(effects
				(font
					(size 1.27 1.27)
				)
				(hide yes)
			)
		)
		(property "Author" "Antmicro"
			(at 375.92 209.55 0)
			(effects
				(font
					(size 1.27 1.27)
					(thickness 0.15)
				)
				(justify left bottom)
				(hide yes)
			)
		)
		(property "License" "Apache-2.0"
			(at 375.92 212.09 0)
			(effects
				(font
					(size 1.27 1.27)
					(thickness 0.15)
				)
				(justify left bottom)
				(hide yes)
			)
		)
		(pin "1"
		)
		(instances
			(project "jetson-agx-thor-baseboard"
				(path ""
					(reference "#PWR0124")
					(unit 1)
				)
			)
		)
	)
	(symbol
		(lib_id "antmicroTransistorsFETsMOSFETsSingle:DMG1012T-7")
		(at 284.48 234.95 0)
		(unit 1)
		(exclude_from_sim no)
		(in_bom yes)
		(on_board yes)
		(dnp no)
		(fields_autoplaced yes)
		(property "Reference" "Q20"
			(at 294.64 231.14 0)
			(effects
				(font
					(size 1.27 1.27)
					(thickness 0.15)
				)
				(justify left)
			)
		)
		(property "Value" "DMG1012T-7"
			(at 307.34 243.84 0)
			(effects
				(font
					(size 1.27 1.27)
					(thickness 0.15)
				)
				(justify left bottom)
				(hide yes)
			)
		)
		(property "Footprint" "antmicro-footprints:SOT-523"
			(at 307.34 246.38 0)
			(effects
				(font
					(size 1.27 1.27)
					(thickness 0.15)
				)
				(justify left bottom)
				(hide yes)
			)
		)
		(property "Datasheet" "https://www.diodes.com/assets/Datasheets/ds31783.pdf"
			(at 307.34 248.92 0)
			(effects
				(font
					(size 1.27 1.27)
					(thickness 0.15)
				)
				(justify left bottom)
				(hide yes)
			)
		)
		(property "Description" "Power MOSFET, N Channel, 20 V, 630 mA, 0.3 ohm, SOT-523, Surface Mount"
			(at 307.34 261.62 0)
			(effects
				(font
					(size 1.27 1.27)
				)
				(justify left bottom)
				(hide yes)
			)
		)
		(property "MPN" "DMG1012T-7"
			(at 294.64 233.68 0)
			(effects
				(font
					(size 1.27 1.27)
					(thickness 0.15)
				)
				(justify left)
			)
		)
		(property "Manufacturer" "Diodes Incorporated"
			(at 307.34 254 0)
			(effects
				(font
					(size 1.27 1.27)
					(thickness 0.15)
				)
				(justify left bottom)
				(hide yes)
			)
		)
		(property "Author" "Antmicro"
			(at 307.34 256.54 0)
			(effects
				(font
					(size 1.27 1.27)
					(thickness 0.15)
				)
				(justify left bottom)
				(hide yes)
			)
		)
		(property "License" "Apache-2.0"
			(at 307.34 259.08 0)
			(effects
				(font
					(size 1.27 1.27)
					(thickness 0.15)
				)
				(justify left bottom)
				(hide yes)
			)
		)
		(pin "3"
		)
		(pin "1"
		)
		(pin "2"
		)
		(instances
			(project ""
				(path ""
					(reference "Q20")
					(unit 1)
				)
			)
		)
	)
	(symbol
		(lib_id "antmicroTestPoints:TP_0.75mm_SMD")
		(at 90.17 100.33 90)
		(unit 1)
		(exclude_from_sim no)
		(in_bom no)
		(on_board yes)
		(dnp no)
		(property "Reference" "TP83"
			(at 88.138 94.996 90)
			(effects
				(font
					(size 1.27 1.27)
					(thickness 0.15)
				)
				(justify right)
			)
		)
		(property "Value" "TP_0.75mm_SMD"
			(at 93.98 90.17 0)
			(effects
				(font
					(size 1.27 1.27)
					(thickness 0.15)
				)
				(justify left bottom)
				(hide yes)
			)
		)
		(property "Footprint" "antmicro-footprints:TP_SMD_0.75mm"
			(at 96.52 90.17 0)
			(effects
				(font
					(size 1.27 1.27)
					(thickness 0.15)
				)
				(justify left bottom)
				(hide yes)
			)
		)
		(property "Datasheet" ""
			(at 102.87 82.55 0)
			(effects
				(font
					(size 1.27 1.27)
					(thickness 0.15)
				)
				(justify left bottom)
				(hide yes)
			)
		)
		(property "Description" "SMT test point"
			(at 90.17 100.33 0)
			(effects
				(font
					(size 1.27 1.27)
				)
				(hide yes)
			)
		)
		(property "MPN" ""
			(at 101.6 89.535 0)
			(effects
				(font
					(size 1.27 1.27)
					(thickness 0.15)
				)
				(justify left bottom)
				(hide yes)
			)
		)
		(property "Manufacturer" ""
			(at 96.52 89.535 0)
			(effects
				(font
					(size 1.27 1.27)
					(thickness 0.15)
				)
				(justify left bottom)
				(hide yes)
			)
		)
		(property "Author" "Antmicro"
			(at 99.06 90.17 0)
			(effects
				(font
					(size 1.27 1.27)
					(thickness 0.15)
				)
				(justify left bottom)
				(hide yes)
			)
		)
		(property "License" "Apache-2.0"
			(at 101.6 90.17 0)
			(effects
				(font
					(size 1.27 1.27)
					(thickness 0.15)
				)
				(justify left bottom)
				(hide yes)
			)
		)
		(pin "1"
		)
		(instances
			(project "jetson-agx-thor-baseboard"
				(path ""
					(reference "TP83")
					(unit 1)
				)
			)
		)
	)
	(symbol
		(lib_id "antmicroCapacitors0402:C_10u_0402")
		(at 115.57 48.26 90)
		(unit 1)
		(exclude_from_sim no)
		(in_bom yes)
		(on_board yes)
		(dnp no)
		(fields_autoplaced yes)
		(property "Reference" "C4"
			(at 118.11 44.4436 90)
			(effects
				(font
					(size 1.27 1.27)
					(thickness 0.15)
				)
				(justify right)
			)
		)
		(property "Value" "C_10u_0402"
			(at 125.73 27.94 0)
			(effects
				(font
					(size 1.27 1.27)
					(thickness 0.15)
				)
				(justify left bottom)
				(hide yes)
			)
		)
		(property "Footprint" "antmicro-footprints:C_0402_1005Metric"
			(at 128.27 27.94 0)
			(effects
				(font
					(size 1.27 1.27)
					(thickness 0.15)
				)
				(justify left bottom)
				(hide yes)
			)
		)
		(property "Datasheet" "https://www.yageo.com/en/Chart/Download/pdf/CC0402MRX5R5BB106"
			(at 130.81 27.94 0)
			(effects
				(font
					(size 1.27 1.27)
					(thickness 0.15)
				)
				(justify left bottom)
				(hide yes)
			)
		)
		(property "Description" "SMD Multilayer Ceramic Capacitor, 10 µF, 6.3 V, 0402 [1005 Metric], ± 20%, X5R, CC Series"
			(at 115.57 48.26 0)
			(effects
				(font
					(size 1.27 1.27)
				)
				(hide yes)
			)
		)
		(property "MPN" "CC0402MRX5R5BB106"
			(at 133.35 27.94 0)
			(effects
				(font
					(size 1.27 1.27)
					(thickness 0.15)
				)
				(justify left bottom)
				(hide yes)
			)
		)
		(property "Manufacturer" "YAGEO"
			(at 135.89 27.94 0)
			(effects
				(font
					(size 1.27 1.27)
					(thickness 0.15)
				)
				(justify left bottom)
				(hide yes)
			)
		)
		(property "License" "Apache-2.0"
			(at 138.43 27.94 0)
			(effects
				(font
					(size 1.27 1.27)
					(thickness 0.15)
				)
				(justify left bottom)
				(hide yes)
			)
		)
		(property "Author" "Antmicro"
			(at 140.97 27.94 0)
			(effects
				(font
					(size 1.27 1.27)
					(thickness 0.15)
				)
				(justify left bottom)
				(hide yes)
			)
		)
		(property "Val" "10u"
			(at 118.11 46.9836 90)
			(effects
				(font
					(size 1.27 1.27)
					(thickness 0.15)
				)
				(justify right)
			)
		)
		(property "Voltage" ""
			(at 143.51 27.94 0)
			(effects
				(font
					(size 1.27 1.27)
				)
				(justify left bottom)
				(hide yes)
			)
		)
		(property "Dielectric" "template_dielectric"
			(at 146.05 27.94 0)
			(effects
				(font
					(size 1.27 1.27)
				)
				(justify left bottom)
				(hide yes)
			)
		)
		(pin "1"
		)
		(pin "2"
		)
		(instances
			(project "jetson-agx-thor-baseboard"
				(path ""
					(reference "C4")
					(unit 1)
				)
			)
		)
	)
	(symbol
		(lib_id "antmicroLogicBuffersDriversReceiversTransceivers:SN74LVC2G07DCKR")
		(at 64.77 151.13 0)
		(unit 1)
		(exclude_from_sim no)
		(in_bom yes)
		(on_board yes)
		(dnp no)
		(fields_autoplaced yes)
		(property "Reference" "U74"
			(at 74.295 143.51 0)
			(effects
				(font
					(size 1.27 1.27)
					(thickness 0.15)
				)
			)
		)
		(property "Value" "SN74LVC2G07DCKR"
			(at 97.79 158.75 0)
			(effects
				(font
					(size 1.27 1.27)
					(thickness 0.15)
				)
				(justify left bottom)
				(hide yes)
			)
		)
		(property "Footprint" "antmicro-footprints:SC-70-6"
			(at 97.79 161.29 0)
			(effects
				(font
					(size 1.27 1.27)
					(thickness 0.15)
				)
				(justify left bottom)
				(hide yes)
			)
		)
		(property "Datasheet" "https://www.ti.com/lit/gpn/sn74lvc2g07"
			(at 97.79 163.83 0)
			(effects
				(font
					(size 1.27 1.27)
					(thickness 0.15)
				)
				(justify left bottom)
				(hide yes)
			)
		)
		(property "Description" "Buffer / Line Driver, SN74LVC2G07DCKR, 1.65 V to 5.5 V, SC-70-5"
			(at 97.79 173.99 0)
			(effects
				(font
					(size 1.27 1.27)
				)
				(justify left bottom)
				(hide yes)
			)
		)
		(property "MPN" "SN74LVC2G07DCKR"
			(at 74.295 146.05 0)
			(effects
				(font
					(size 1.27 1.27)
					(thickness 0.15)
				)
			)
		)
		(property "Manufacturer" "Texas Instruments"
			(at 97.79 166.37 0)
			(effects
				(font
					(size 1.27 1.27)
					(thickness 0.15)
				)
				(justify left bottom)
				(hide yes)
			)
		)
		(property "Author" "Antmicro"
			(at 97.79 168.91 0)
			(effects
				(font
					(size 1.27 1.27)
					(thickness 0.15)
				)
				(justify left bottom)
				(hide yes)
			)
		)
		(property "License" "Apache-2.0"
			(at 97.79 171.45 0)
			(effects
				(font
					(size 1.27 1.27)
					(thickness 0.15)
				)
				(justify left bottom)
				(hide yes)
			)
		)
		(pin "4"
		)
		(pin "6"
		)
		(pin "3"
		)
		(pin "5"
		)
		(pin "1"
		)
		(pin "2"
		)
		(instances
			(project "jetson-agx-thor-baseboard"
				(path ""
					(reference "U74")
					(unit 1)
				)
			)
		)
	)
	(symbol
		(lib_id "antmicroModules:Jetson-Thor-AGX-T5000")
		(at 369.57 20.32 0)
		(unit 1)
		(exclude_from_sim no)
		(in_bom no)
		(on_board yes)
		(dnp yes)
		(fields_autoplaced yes)
		(property "Reference" "A3"
			(at 381 20.955 0)
			(effects
				(font
					(size 1.27 1.27)
					(thickness 0.15)
				)
				(justify left)
			)
		)
		(property "Value" "Jetson-Thor-AGX-T5000"
			(at 394.97 27.94 0)
			(effects
				(font
					(size 1.27 1.27)
					(thickness 0.15)
				)
				(justify left bottom)
				(hide yes)
			)
		)
		(property "Footprint" "antmicro-footprints:Module_Jetson-Thor-AGX-T5000"
			(at 394.97 30.48 0)
			(effects
				(font
					(size 1.27 1.27)
					(thickness 0.15)
				)
				(justify left bottom)
				(hide yes)
			)
		)
		(property "Datasheet" "https://developer.nvidia.com/embedded/downloads#?tx=$product,jetson_thor"
			(at 394.97 33.02 0)
			(effects
				(font
					(size 1.27 1.27)
					(thickness 0.15)
				)
				(justify left bottom)
				(hide yes)
			)
		)
		(property "Description" "Jetson Thor, System-on-Module, 2560-core NVIDIA Blackwell GPU with 96 fifth-gen Tensor Cores, Multi-Instance GPU with 10TPCs, 14-core Arm Neoverse-V3AE 64-bit CPU, 128 GB LPDDR5X"
			(at 394.97 48.26 0)
			(effects
				(font
					(size 1.27 1.27)
				)
				(justify left bottom)
				(hide yes)
			)
		)
		(property "Manufacturer" "Nvidia"
			(at 394.97 35.56 0)
			(effects
				(font
					(size 1.27 1.27)
					(thickness 0.15)
				)
				(justify left bottom)
				(hide yes)
			)
		)
		(property "MPN" "900-13834-0080-000"
			(at 381 23.495 0)
			(effects
				(font
					(size 1.27 1.27)
					(thickness 0.15)
				)
				(justify left)
			)
		)
		(property "Author" "Antmicro"
			(at 394.97 40.64 0)
			(effects
				(font
					(size 1.27 1.27)
					(thickness 0.15)
				)
				(justify left bottom)
				(hide yes)
			)
		)
		(property "License" "Apache-2.0"
			(at 394.97 43.18 0)
			(effects
				(font
					(size 1.27 1.27)
					(thickness 0.15)
				)
				(justify left bottom)
				(hide yes)
			)
		)
		(property "Displayed name" "Jetson Thor AGX T5000"
			(at 381 26.0349 0)
			(effects
				(font
					(size 1.27 1.27)
				)
				(justify left)
			)
		)
		(instances
			(project ""
				(path ""
					(reference "A3")
					(unit 1)
				)
			)
		)
	)
	(symbol
		(lib_id "antmicropower:GND")
		(at 207.01 194.31 0)
		(unit 1)
		(exclude_from_sim no)
		(in_bom yes)
		(on_board yes)
		(dnp no)
		(property "Reference" "#PWR0567"
			(at 215.9 196.85 0)
			(effects
				(font
					(size 1.27 1.27)
					(thickness 0.15)
				)
				(justify left bottom)
				(hide yes)
			)
		)
		(property "Value" "GND"
			(at 207.01 198.12 0)
			(effects
				(font
					(size 1.27 1.27)
					(thickness 0.15)
				)
			)
		)
		(property "Footprint" ""
			(at 215.9 201.93 0)
			(effects
				(font
					(size 1.27 1.27)
					(thickness 0.15)
				)
				(justify left bottom)
				(hide yes)
			)
		)
		(property "Datasheet" ""
			(at 215.9 207.01 0)
			(effects
				(font
					(size 1.27 1.27)
					(thickness 0.15)
				)
				(justify left bottom)
				(hide yes)
			)
		)
		(property "Description" ""
			(at 207.01 194.31 0)
			(effects
				(font
					(size 1.27 1.27)
				)
				(hide yes)
			)
		)
		(property "Author" "Antmicro"
			(at 215.9 201.93 0)
			(effects
				(font
					(size 1.27 1.27)
					(thickness 0.15)
				)
				(justify left bottom)
				(hide yes)
			)
		)
		(property "License" "Apache-2.0"
			(at 215.9 204.47 0)
			(effects
				(font
					(size 1.27 1.27)
					(thickness 0.15)
				)
				(justify left bottom)
				(hide yes)
			)
		)
		(pin "1"
		)
		(instances
			(project "jetson-agx-thor-baseboard"
				(path ""
					(reference "#PWR0567")
					(unit 1)
				)
			)
		)
	)
	(symbol
		(lib_id "antmicroTestPoints:TP_0.75mm_SMD")
		(at 269.24 71.12 0)
		(unit 1)
		(exclude_from_sim no)
		(in_bom no)
		(on_board yes)
		(dnp no)
		(property "Reference" "TP80"
			(at 274.32 71.12 0)
			(effects
				(font
					(size 1.27 1.27)
					(thickness 0.15)
				)
				(justify left)
			)
		)
		(property "Value" "TP_0.75mm_SMD"
			(at 279.4 74.93 0)
			(effects
				(font
					(size 1.27 1.27)
					(thickness 0.15)
				)
				(justify left bottom)
				(hide yes)
			)
		)
		(property "Footprint" "antmicro-footprints:TP_SMD_0.75mm"
			(at 279.4 77.47 0)
			(effects
				(font
					(size 1.27 1.27)
					(thickness 0.15)
				)
				(justify left bottom)
				(hide yes)
			)
		)
		(property "Datasheet" ""
			(at 287.02 83.82 0)
			(effects
				(font
					(size 1.27 1.27)
					(thickness 0.15)
				)
				(justify left bottom)
				(hide yes)
			)
		)
		(property "Description" "SMT test point"
			(at 269.24 71.12 0)
			(effects
				(font
					(size 1.27 1.27)
				)
				(hide yes)
			)
		)
		(property "MPN" ""
			(at 280.035 82.55 0)
			(effects
				(font
					(size 1.27 1.27)
					(thickness 0.15)
				)
				(justify left bottom)
				(hide yes)
			)
		)
		(property "Manufacturer" ""
			(at 280.035 77.47 0)
			(effects
				(font
					(size 1.27 1.27)
					(thickness 0.15)
				)
				(justify left bottom)
				(hide yes)
			)
		)
		(property "Author" "Antmicro"
			(at 279.4 80.01 0)
			(effects
				(font
					(size 1.27 1.27)
					(thickness 0.15)
				)
				(justify left bottom)
				(hide yes)
			)
		)
		(property "License" "Apache-2.0"
			(at 279.4 82.55 0)
			(effects
				(font
					(size 1.27 1.27)
					(thickness 0.15)
				)
				(justify left bottom)
				(hide yes)
			)
		)
		(pin "1"
		)
		(instances
			(project "jetson-agx-thor-baseboard"
				(path ""
					(reference "TP80")
					(unit 1)
				)
			)
		)
	)
	(symbol
		(lib_id "antmicroTestPoints:TP_0.75mm_SMD")
		(at 194.31 106.68 0)
		(mirror y)
		(unit 1)
		(exclude_from_sim no)
		(in_bom no)
		(on_board yes)
		(dnp no)
		(fields_autoplaced yes)
		(property "Reference" "TP32"
			(at 189.23 106.68 0)
			(effects
				(font
					(size 1.27 1.27)
					(thickness 0.15)
				)
				(justify left)
			)
		)
		(property "Value" "TP_0.75mm_SMD"
			(at 184.15 110.49 0)
			(effects
				(font
					(size 1.27 1.27)
					(thickness 0.15)
				)
				(justify left bottom)
				(hide yes)
			)
		)
		(property "Footprint" "antmicro-footprints:TP_SMD_0.75mm"
			(at 184.15 113.03 0)
			(effects
				(font
					(size 1.27 1.27)
					(thickness 0.15)
				)
				(justify left bottom)
				(hide yes)
			)
		)
		(property "Datasheet" ""
			(at 176.53 119.38 0)
			(effects
				(font
					(size 1.27 1.27)
					(thickness 0.15)
				)
				(justify left bottom)
				(hide yes)
			)
		)
		(property "Description" "SMT test point"
			(at 194.31 106.68 0)
			(effects
				(font
					(size 1.27 1.27)
				)
				(hide yes)
			)
		)
		(property "MPN" ""
			(at 183.515 118.11 0)
			(effects
				(font
					(size 1.27 1.27)
					(thickness 0.15)
				)
				(justify left bottom)
				(hide yes)
			)
		)
		(property "Manufacturer" ""
			(at 183.515 113.03 0)
			(effects
				(font
					(size 1.27 1.27)
					(thickness 0.15)
				)
				(justify left bottom)
				(hide yes)
			)
		)
		(property "Author" "Antmicro"
			(at 184.15 115.57 0)
			(effects
				(font
					(size 1.27 1.27)
					(thickness 0.15)
				)
				(justify left bottom)
				(hide yes)
			)
		)
		(property "License" "Apache-2.0"
			(at 184.15 118.11 0)
			(effects
				(font
					(size 1.27 1.27)
					(thickness 0.15)
				)
				(justify left bottom)
				(hide yes)
			)
		)
		(pin "1"
		)
		(instances
			(project "jetson-agx-thor-baseboard"
				(path ""
					(reference "TP32")
					(unit 1)
				)
			)
		)
	)
	(symbol
		(lib_id "antmicropower:GND")
		(at 193.04 232.41 0)
		(unit 1)
		(exclude_from_sim no)
		(in_bom yes)
		(on_board yes)
		(dnp no)
		(property "Reference" "#PWR0490"
			(at 201.93 234.95 0)
			(effects
				(font
					(size 1.27 1.27)
					(thickness 0.15)
				)
				(justify left bottom)
				(hide yes)
			)
		)
		(property "Value" "GND"
			(at 193.04 236.22 0)
			(effects
				(font
					(size 1.27 1.27)
					(thickness 0.15)
				)
			)
		)
		(property "Footprint" ""
			(at 201.93 240.03 0)
			(effects
				(font
					(size 1.27 1.27)
					(thickness 0.15)
				)
				(justify left bottom)
				(hide yes)
			)
		)
		(property "Datasheet" ""
			(at 201.93 245.11 0)
			(effects
				(font
					(size 1.27 1.27)
					(thickness 0.15)
				)
				(justify left bottom)
				(hide yes)
			)
		)
		(property "Description" ""
			(at 201.93 247.65 0)
			(effects
				(font
					(size 1.27 1.27)
				)
				(justify left bottom)
				(hide yes)
			)
		)
		(property "Author" "Antmicro"
			(at 201.93 240.03 0)
			(effects
				(font
					(size 1.27 1.27)
					(thickness 0.15)
				)
				(justify left bottom)
				(hide yes)
			)
		)
		(property "License" "Apache-2.0"
			(at 201.93 242.57 0)
			(effects
				(font
					(size 1.27 1.27)
					(thickness 0.15)
				)
				(justify left bottom)
				(hide yes)
			)
		)
		(pin "1"
		)
		(instances
			(project "jetson-agx-thor-baseboard"
				(path ""
					(reference "#PWR0490")
					(unit 1)
				)
			)
		)
	)
	(symbol
		(lib_id "antmicropower:+3V3_AON")
		(at 95.25 232.41 0)
		(unit 1)
		(exclude_from_sim no)
		(in_bom yes)
		(on_board yes)
		(dnp no)
		(fields_autoplaced yes)
		(property "Reference" "#PWR0576"
			(at 95.25 236.22 0)
			(effects
				(font
					(size 1.27 1.27)
				)
				(hide yes)
			)
		)
		(property "Value" "+3V3_AON"
			(at 95.25 227.33 0)
			(effects
				(font
					(size 1.27 1.27)
				)
			)
		)
		(property "Footprint" ""
			(at 95.25 232.41 0)
			(effects
				(font
					(size 1.27 1.27)
				)
				(hide yes)
			)
		)
		(property "Datasheet" ""
			(at 95.25 232.41 0)
			(effects
				(font
					(size 1.27 1.27)
				)
				(hide yes)
			)
		)
		(property "Description" ""
			(at 95.25 232.41 0)
			(effects
				(font
					(size 1.27 1.27)
				)
				(hide yes)
			)
		)
		(pin "1"
		)
		(instances
			(project "jetson-agx-thor-baseboard"
				(path ""
					(reference "#PWR0576")
					(unit 1)
				)
			)
		)
	)
	(symbol
		(lib_id "antmicroTVSDiodes:PESD5Z5_0F")
		(at 82.55 35.56 270)
		(unit 1)
		(exclude_from_sim no)
		(in_bom yes)
		(on_board yes)
		(dnp no)
		(property "Reference" "D55"
			(at 83.82 36.83 90)
			(effects
				(font
					(size 1.27 1.27)
				)
				(justify left)
			)
		)
		(property "Value" "PESD5Z5.0F"
			(at 67.31 57.15 0)
			(effects
				(font
					(size 1.27 1.27)
					(thickness 0.15)
				)
				(justify left bottom)
				(hide yes)
			)
		)
		(property "Footprint" "antmicro-footprints:SOD-523"
			(at 77.47 50.8 0)
			(effects
				(font
					(size 1.27 1.27)
					(thickness 0.15)
				)
				(justify left bottom)
				(hide yes)
			)
		)
		(property "Datasheet" "https://assets.nexperia.com/documents/data-sheet/PESD5Z5_0.pdf"
			(at 74.93 50.8 0)
			(effects
				(font
					(size 1.27 1.27)
					(thickness 0.15)
				)
				(justify left bottom)
				(hide yes)
			)
		)
		(property "Description" "Unidirectional TVS, 30 kV,  SOD-523, 5 V, 89 pF"
			(at 62.23 50.8 0)
			(effects
				(font
					(size 1.27 1.27)
				)
				(justify left bottom)
				(hide yes)
			)
		)
		(property "Manufacturer" "Nexperia"
			(at 72.39 50.8 0)
			(effects
				(font
					(size 1.27 1.27)
					(thickness 0.15)
				)
				(justify left bottom)
				(hide yes)
			)
		)
		(property "MPN" "PESD5Z5.0F"
			(at 83.82 39.37 90)
			(effects
				(font
					(size 1.27 1.27)
					(thickness 0.15)
				)
				(justify left bottom)
			)
		)
		(property "Author" "Antmicro"
			(at 67.31 50.8 0)
			(effects
				(font
					(size 1.27 1.27)
					(thickness 0.15)
				)
				(justify left bottom)
				(hide yes)
			)
		)
		(property "License" "Apache-2.0"
			(at 64.77 50.8 0)
			(effects
				(font
					(size 1.27 1.27)
					(thickness 0.15)
				)
				(justify left bottom)
				(hide yes)
			)
		)
		(pin "1"
		)
		(pin "2"
		)
		(instances
			(project "jetson-agx-thor-baseboard"
				(path ""
					(reference "D55")
					(unit 1)
				)
			)
		)
	)
	(symbol
		(lib_id "antmicroTransistorsFETsMOSFETsSingle:DMG1012T-7")
		(at 354.33 223.52 0)
		(unit 1)
		(exclude_from_sim no)
		(in_bom yes)
		(on_board yes)
		(dnp no)
		(property "Reference" "Q10"
			(at 364.49 225.806 90)
			(effects
				(font
					(size 1.27 1.27)
					(thickness 0.15)
				)
				(justify left)
			)
		)
		(property "Value" "DMG1012T-7"
			(at 377.19 240.03 0)
			(effects
				(font
					(size 1.27 1.27)
					(thickness 0.15)
				)
				(justify left bottom)
				(hide yes)
			)
		)
		(property "Footprint" "antmicro-footprints:SOT-523"
			(at 377.19 234.95 0)
			(effects
				(font
					(size 1.27 1.27)
					(thickness 0.15)
				)
				(justify left bottom)
				(hide yes)
			)
		)
		(property "Datasheet" "https://www.diodes.com/assets/Datasheets/ds31783.pdf"
			(at 377.19 237.49 0)
			(effects
				(font
					(size 1.27 1.27)
					(thickness 0.15)
				)
				(justify left bottom)
				(hide yes)
			)
		)
		(property "Description" "Power MOSFET, N Channel, 20 V, 630 mA, 0.3 ohm, SOT-523, Surface Mount"
			(at 413.512 249.428 0)
			(effects
				(font
					(size 1.27 1.27)
				)
				(hide yes)
			)
		)
		(property "MPN" "DMG1012T-7"
			(at 367.03 225.806 90)
			(effects
				(font
					(size 1.27 1.27)
					(thickness 0.15)
				)
				(justify left)
			)
		)
		(property "Manufacturer" "Diodes Incorporated"
			(at 377.19 242.57 0)
			(effects
				(font
					(size 1.27 1.27)
					(thickness 0.15)
				)
				(justify left bottom)
				(hide yes)
			)
		)
		(property "Author" "Antmicro"
			(at 377.19 245.11 0)
			(effects
				(font
					(size 1.27 1.27)
					(thickness 0.15)
				)
				(justify left bottom)
				(hide yes)
			)
		)
		(property "License" "Apache-2.0"
			(at 377.19 247.65 0)
			(effects
				(font
					(size 1.27 1.27)
					(thickness 0.15)
				)
				(justify left bottom)
				(hide yes)
			)
		)
		(pin "1"
		)
		(pin "3"
		)
		(pin "2"
		)
		(instances
			(project "jetson-agx-thor-baseboard"
				(path ""
					(reference "Q10")
					(unit 1)
				)
			)
		)
	)
	(symbol
		(lib_id "antmicroResistors0402:R_10k_0402")
		(at 336.55 238.76 90)
		(unit 1)
		(exclude_from_sim no)
		(in_bom yes)
		(on_board yes)
		(dnp no)
		(property "Reference" "R355"
			(at 330.2 234.696 90)
			(effects
				(font
					(size 1.27 1.27)
				)
				(justify right)
			)
		)
		(property "Value" "R_10k_0402"
			(at 349.25 218.44 0)
			(effects
				(font
					(size 1.27 1.27)
					(thickness 0.15)
				)
				(justify left bottom)
				(hide yes)
			)
		)
		(property "Footprint" "antmicro-footprints:R_0402_1005Metric"
			(at 351.79 218.44 0)
			(effects
				(font
					(size 1.27 1.27)
					(thickness 0.15)
				)
				(justify left bottom)
				(hide yes)
			)
		)
		(property "Datasheet" "https://www.bourns.com/docs/product-datasheets/cr.pdf"
			(at 354.33 218.44 0)
			(effects
				(font
					(size 1.27 1.27)
					(thickness 0.15)
				)
				(justify left bottom)
				(hide yes)
			)
		)
		(property "Description" "SMD Chip Resistor, 10 kohm, ± 1%, 62.5 mW, 0402 [1005 Metric], Thick Film, General Purpose"
			(at 336.55 238.76 0)
			(effects
				(font
					(size 1.27 1.27)
				)
				(hide yes)
			)
		)
		(property "Manufacturer" "Bourns"
			(at 359.41 218.44 0)
			(effects
				(font
					(size 1.27 1.27)
					(thickness 0.15)
				)
				(justify left bottom)
				(hide yes)
			)
		)
		(property "MPN" "CR0402-FX-1002GLF"
			(at 356.87 218.44 0)
			(effects
				(font
					(size 1.27 1.27)
					(thickness 0.15)
				)
				(justify left bottom)
				(hide yes)
			)
		)
		(property "Val" "10k"
			(at 330.2 237.236 90)
			(effects
				(font
					(size 1.27 1.27)
					(thickness 0.15)
				)
				(justify right)
			)
		)
		(property "License" "Apache-2.0"
			(at 361.95 218.44 0)
			(effects
				(font
					(size 1.27 1.27)
					(thickness 0.15)
				)
				(justify left bottom)
				(hide yes)
			)
		)
		(property "Author" "Antmicro"
			(at 364.49 218.44 0)
			(effects
				(font
					(size 1.27 1.27)
					(thickness 0.15)
				)
				(justify left bottom)
				(hide yes)
			)
		)
		(property "Tolerance" "1%"
			(at 346.71 218.44 0)
			(effects
				(font
					(size 1.27 1.27)
				)
				(justify left bottom)
				(hide yes)
			)
		)
		(pin "1"
		)
		(pin "2"
		)
		(instances
			(project "jetson-agx-thor-baseboard"
				(path ""
					(reference "R355")
					(unit 1)
				)
			)
		)
	)
	(symbol
		(lib_id "antmicropower:GND")
		(at 88.9 210.82 0)
		(unit 1)
		(exclude_from_sim no)
		(in_bom yes)
		(on_board yes)
		(dnp no)
		(property "Reference" "#PWR062"
			(at 88.9 217.17 0)
			(effects
				(font
					(size 1.27 1.27)
				)
				(justify left bottom)
				(hide yes)
			)
		)
		(property "Value" "GND"
			(at 88.9 214.63 0)
			(effects
				(font
					(size 1.27 1.27)
					(thickness 0.15)
				)
			)
		)
		(property "Footprint" ""
			(at 97.79 218.44 0)
			(effects
				(font
					(size 1.27 1.27)
					(thickness 0.15)
				)
				(justify left bottom)
				(hide yes)
			)
		)
		(property "Datasheet" ""
			(at 97.79 223.52 0)
			(effects
				(font
					(size 1.27 1.27)
					(thickness 0.15)
				)
				(justify left bottom)
				(hide yes)
			)
		)
		(property "Description" ""
			(at 88.9 210.82 0)
			(effects
				(font
					(size 1.27 1.27)
				)
				(hide yes)
			)
		)
		(property "Author" "Antmicro"
			(at 97.79 218.44 0)
			(effects
				(font
					(size 1.27 1.27)
					(thickness 0.15)
				)
				(justify left bottom)
				(hide yes)
			)
		)
		(property "License" "Apache-2.0"
			(at 97.79 220.98 0)
			(effects
				(font
					(size 1.27 1.27)
					(thickness 0.15)
				)
				(justify left bottom)
				(hide yes)
			)
		)
		(pin "1"
		)
		(instances
			(project "jetson-agx-thor-baseboard"
				(path ""
					(reference "#PWR062")
					(unit 1)
				)
			)
		)
	)
	(symbol
		(lib_id "antmicroTestPoints:TP_0.75mm_SMD")
		(at 194.31 102.87 0)
		(mirror y)
		(unit 1)
		(exclude_from_sim no)
		(in_bom no)
		(on_board yes)
		(dnp no)
		(fields_autoplaced yes)
		(property "Reference" "TP31"
			(at 189.23 102.87 0)
			(effects
				(font
					(size 1.27 1.27)
					(thickness 0.15)
				)
				(justify left)
			)
		)
		(property "Value" "TP_0.75mm_SMD"
			(at 184.15 106.68 0)
			(effects
				(font
					(size 1.27 1.27)
					(thickness 0.15)
				)
				(justify left bottom)
				(hide yes)
			)
		)
		(property "Footprint" "antmicro-footprints:TP_SMD_0.75mm"
			(at 184.15 109.22 0)
			(effects
				(font
					(size 1.27 1.27)
					(thickness 0.15)
				)
				(justify left bottom)
				(hide yes)
			)
		)
		(property "Datasheet" ""
			(at 176.53 115.57 0)
			(effects
				(font
					(size 1.27 1.27)
					(thickness 0.15)
				)
				(justify left bottom)
				(hide yes)
			)
		)
		(property "Description" "SMT test point"
			(at 194.31 102.87 0)
			(effects
				(font
					(size 1.27 1.27)
				)
				(hide yes)
			)
		)
		(property "MPN" ""
			(at 183.515 114.3 0)
			(effects
				(font
					(size 1.27 1.27)
					(thickness 0.15)
				)
				(justify left bottom)
				(hide yes)
			)
		)
		(property "Manufacturer" ""
			(at 183.515 109.22 0)
			(effects
				(font
					(size 1.27 1.27)
					(thickness 0.15)
				)
				(justify left bottom)
				(hide yes)
			)
		)
		(property "Author" "Antmicro"
			(at 184.15 111.76 0)
			(effects
				(font
					(size 1.27 1.27)
					(thickness 0.15)
				)
				(justify left bottom)
				(hide yes)
			)
		)
		(property "License" "Apache-2.0"
			(at 184.15 114.3 0)
			(effects
				(font
					(size 1.27 1.27)
					(thickness 0.15)
				)
				(justify left bottom)
				(hide yes)
			)
		)
		(pin "1"
		)
		(instances
			(project "jetson-agx-thor-baseboard"
				(path ""
					(reference "TP31")
					(unit 1)
				)
			)
		)
	)
	(symbol
		(lib_id "antmicropower:GND")
		(at 307.34 182.88 0)
		(unit 1)
		(exclude_from_sim no)
		(in_bom yes)
		(on_board yes)
		(dnp no)
		(property "Reference" "#PWR0125"
			(at 307.34 189.23 0)
			(effects
				(font
					(size 1.27 1.27)
				)
				(justify left bottom)
				(hide yes)
			)
		)
		(property "Value" "GND"
			(at 307.34 186.69 0)
			(effects
				(font
					(size 1.27 1.27)
					(thickness 0.15)
				)
			)
		)
		(property "Footprint" ""
			(at 316.23 190.5 0)
			(effects
				(font
					(size 1.27 1.27)
					(thickness 0.15)
				)
				(justify left bottom)
				(hide yes)
			)
		)
		(property "Datasheet" ""
			(at 316.23 195.58 0)
			(effects
				(font
					(size 1.27 1.27)
					(thickness 0.15)
				)
				(justify left bottom)
				(hide yes)
			)
		)
		(property "Description" ""
			(at 307.34 182.88 0)
			(effects
				(font
					(size 1.27 1.27)
				)
				(hide yes)
			)
		)
		(property "Author" "Antmicro"
			(at 316.23 190.5 0)
			(effects
				(font
					(size 1.27 1.27)
					(thickness 0.15)
				)
				(justify left bottom)
				(hide yes)
			)
		)
		(property "License" "Apache-2.0"
			(at 316.23 193.04 0)
			(effects
				(font
					(size 1.27 1.27)
					(thickness 0.15)
				)
				(justify left bottom)
				(hide yes)
			)
		)
		(pin "1"
		)
		(instances
			(project "jetson-agx-thor-baseboard"
				(path ""
					(reference "#PWR0125")
					(unit 1)
				)
			)
		)
	)
	(symbol
		(lib_id "antmicroLEDIndicationDiscrete:LED_G_0603_LTST-C190GKT")
		(at 290.83 226.06 90)
		(unit 1)
		(exclude_from_sim no)
		(in_bom yes)
		(on_board yes)
		(dnp no)
		(property "Reference" "D52"
			(at 294.64 222.25 90)
			(effects
				(font
					(size 1.27 1.27)
					(thickness 0.15)
				)
				(justify right)
			)
		)
		(property "Value" "LED_G_0603_LTST-C190GKT"
			(at 298.45 203.2 0)
			(effects
				(font
					(size 1.27 1.27)
					(thickness 0.15)
				)
				(justify left bottom)
				(hide yes)
			)
		)
		(property "Footprint" "antmicro-footprints:LED_0603_1608Metric_G"
			(at 300.99 203.2 0)
			(effects
				(font
					(size 1.27 1.27)
					(thickness 0.15)
				)
				(justify left bottom)
				(hide yes)
			)
		)
		(property "Datasheet" "https://media.digikey.com/pdf/Data%20Sheets/Lite-On%20PDFs/LTST-C190GKT.pdf"
			(at 303.53 203.2 0)
			(effects
				(font
					(size 1.27 1.27)
					(thickness 0.15)
				)
				(justify left bottom)
				(hide yes)
			)
		)
		(property "Description" "LED, Green, SMD, 0603, 20 mA, 2.1 V, 569 nm"
			(at 290.83 226.06 0)
			(effects
				(font
					(size 1.27 1.27)
				)
				(hide yes)
			)
		)
		(property "MPN" "LTST-C190GKT"
			(at 306.07 203.2 0)
			(effects
				(font
					(size 1.27 1.27)
					(thickness 0.15)
				)
				(justify left bottom)
				(hide yes)
			)
		)
		(property "Manufacturer" "Lite-On"
			(at 308.61 203.2 0)
			(effects
				(font
					(size 1.27 1.27)
					(thickness 0.15)
				)
				(justify left bottom)
				(hide yes)
			)
		)
		(property "Color" "Green"
			(at 293.37 224.7899 90)
			(effects
				(font
					(size 1.27 1.27)
				)
				(justify right)
			)
		)
		(property "Author" "Antmicro"
			(at 311.15 203.2 0)
			(effects
				(font
					(size 1.27 1.27)
					(thickness 0.15)
				)
				(justify left bottom)
				(hide yes)
			)
		)
		(property "License" "Apache-2.0"
			(at 313.69 203.2 0)
			(effects
				(font
					(size 1.27 1.27)
					(thickness 0.15)
				)
				(justify left bottom)
				(hide yes)
			)
		)
		(pin "1"
		)
		(pin "2"
		)
		(instances
			(project "jetson-agx-thor-baseboard"
				(path ""
					(reference "D52")
					(unit 1)
				)
			)
		)
	)
	(symbol
		(lib_id "antmicropower:GND")
		(at 54.61 52.07 0)
		(unit 1)
		(exclude_from_sim no)
		(in_bom yes)
		(on_board yes)
		(dnp no)
		(property "Reference" "#PWR0194"
			(at 54.61 58.42 0)
			(effects
				(font
					(size 1.27 1.27)
				)
				(hide yes)
			)
		)
		(property "Value" "GND"
			(at 54.61 55.88 0)
			(effects
				(font
					(size 1.27 1.27)
					(thickness 0.15)
				)
			)
		)
		(property "Footprint" ""
			(at 63.5 59.69 0)
			(effects
				(font
					(size 1.27 1.27)
					(thickness 0.15)
				)
				(justify left bottom)
				(hide yes)
			)
		)
		(property "Datasheet" ""
			(at 63.5 64.77 0)
			(effects
				(font
					(size 1.27 1.27)
					(thickness 0.15)
				)
				(justify left bottom)
				(hide yes)
			)
		)
		(property "Description" ""
			(at 54.61 52.07 0)
			(effects
				(font
					(size 1.27 1.27)
				)
			)
		)
		(property "Author" "Antmicro"
			(at 63.5 59.69 0)
			(effects
				(font
					(size 1.27 1.27)
					(thickness 0.15)
				)
				(justify left bottom)
				(hide yes)
			)
		)
		(property "License" "Apache-2.0"
			(at 63.5 62.23 0)
			(effects
				(font
					(size 1.27 1.27)
					(thickness 0.15)
				)
				(justify left bottom)
				(hide yes)
			)
		)
		(pin "1"
		)
		(instances
			(project "jetson-agx-thor-baseboard"
				(path ""
					(reference "#PWR0194")
					(unit 1)
				)
			)
		)
	)
	(symbol
		(lib_id "antmicroCapacitors0402:C_10u_0402")
		(at 160.02 48.26 90)
		(unit 1)
		(exclude_from_sim no)
		(in_bom yes)
		(on_board yes)
		(dnp no)
		(fields_autoplaced yes)
		(property "Reference" "C14"
			(at 162.56 44.4436 90)
			(effects
				(font
					(size 1.27 1.27)
					(thickness 0.15)
				)
				(justify right)
			)
		)
		(property "Value" "C_10u_0402"
			(at 170.18 27.94 0)
			(effects
				(font
					(size 1.27 1.27)
					(thickness 0.15)
				)
				(justify left bottom)
				(hide yes)
			)
		)
		(property "Footprint" "antmicro-footprints:C_0402_1005Metric"
			(at 172.72 27.94 0)
			(effects
				(font
					(size 1.27 1.27)
					(thickness 0.15)
				)
				(justify left bottom)
				(hide yes)
			)
		)
		(property "Datasheet" "https://www.yageo.com/en/Chart/Download/pdf/CC0402MRX5R5BB106"
			(at 175.26 27.94 0)
			(effects
				(font
					(size 1.27 1.27)
					(thickness 0.15)
				)
				(justify left bottom)
				(hide yes)
			)
		)
		(property "Description" "SMD Multilayer Ceramic Capacitor, 10 µF, 6.3 V, 0402 [1005 Metric], ± 20%, X5R, CC Series"
			(at 160.02 48.26 0)
			(effects
				(font
					(size 1.27 1.27)
				)
				(hide yes)
			)
		)
		(property "MPN" "CC0402MRX5R5BB106"
			(at 177.8 27.94 0)
			(effects
				(font
					(size 1.27 1.27)
					(thickness 0.15)
				)
				(justify left bottom)
				(hide yes)
			)
		)
		(property "Manufacturer" "YAGEO"
			(at 180.34 27.94 0)
			(effects
				(font
					(size 1.27 1.27)
					(thickness 0.15)
				)
				(justify left bottom)
				(hide yes)
			)
		)
		(property "License" "Apache-2.0"
			(at 182.88 27.94 0)
			(effects
				(font
					(size 1.27 1.27)
					(thickness 0.15)
				)
				(justify left bottom)
				(hide yes)
			)
		)
		(property "Author" "Antmicro"
			(at 185.42 27.94 0)
			(effects
				(font
					(size 1.27 1.27)
					(thickness 0.15)
				)
				(justify left bottom)
				(hide yes)
			)
		)
		(property "Val" "10u"
			(at 162.56 46.9836 90)
			(effects
				(font
					(size 1.27 1.27)
					(thickness 0.15)
				)
				(justify right)
			)
		)
		(property "Voltage" ""
			(at 187.96 27.94 0)
			(effects
				(font
					(size 1.27 1.27)
				)
				(justify left bottom)
				(hide yes)
			)
		)
		(property "Dielectric" "template_dielectric"
			(at 190.5 27.94 0)
			(effects
				(font
					(size 1.27 1.27)
				)
				(justify left bottom)
				(hide yes)
			)
		)
		(pin "1"
		)
		(pin "2"
		)
		(instances
			(project "jetson-agx-thor-baseboard"
				(path ""
					(reference "C14")
					(unit 1)
				)
			)
		)
	)
	(symbol
		(lib_id "antmicroPMICPowerSequencers:TPS3840PL30DBVR")
		(at 100.33 243.84 0)
		(unit 1)
		(exclude_from_sim no)
		(in_bom yes)
		(on_board yes)
		(dnp no)
		(property "Reference" "U72"
			(at 109.22 237.49 0)
			(effects
				(font
					(size 1.27 1.27)
					(thickness 0.15)
				)
			)
		)
		(property "Value" "TPS3840PL30DBVR"
			(at 109.22 238.76 0)
			(effects
				(font
					(size 1.27 1.27)
					(thickness 0.15)
				)
				(hide yes)
			)
		)
		(property "Footprint" "antmicro-footprints:SOT-23-5"
			(at 138.43 250.19 0)
			(effects
				(font
					(size 1.27 1.27)
					(thickness 0.15)
				)
				(justify left bottom)
				(hide yes)
			)
		)
		(property "Datasheet" "https://www.ti.com/lit/ds/symlink/tps3840.pdf?HQS=dis-mous-null-mousermode-dsf-pf-null-wwe&DCM=yes&ref_url=https%3A%2F%2Fwww.mouser.com%2F&distId=26"
			(at 138.43 252.73 0)
			(effects
				(font
					(size 1.27 1.27)
					(thickness 0.15)
				)
				(justify left bottom)
				(hide yes)
			)
		)
		(property "Description" "Voltage supervisor"
			(at 100.33 243.84 0)
			(effects
				(font
					(size 1.27 1.27)
				)
				(hide yes)
			)
		)
		(property "Manufacturer" "Texas Instruments"
			(at 138.43 255.27 0)
			(effects
				(font
					(size 1.27 1.27)
					(thickness 0.15)
				)
				(justify left bottom)
				(hide yes)
			)
		)
		(property "MPN" "TPS3840PL30DBVR"
			(at 100.33 240.03 0)
			(effects
				(font
					(size 1.27 1.27)
					(thickness 0.15)
				)
				(justify left)
			)
		)
		(property "Author" "Antmicro"
			(at 138.43 260.35 0)
			(effects
				(font
					(size 1.27 1.27)
					(thickness 0.15)
				)
				(justify left bottom)
				(hide yes)
			)
		)
		(property "License" "Apache-2.0"
			(at 138.43 262.89 0)
			(effects
				(font
					(size 1.27 1.27)
					(thickness 0.15)
				)
				(justify left bottom)
				(hide yes)
			)
		)
		(pin "4"
		)
		(pin "5"
		)
		(pin "3"
		)
		(pin "1"
		)
		(pin "2"
		)
		(instances
			(project "jetson-agx-thor-baseboard"
				(path ""
					(reference "U72")
					(unit 1)
				)
			)
		)
	)
	(symbol
		(lib_id "antmicroTestPoints:TP_0.75mm_SMD")
		(at 148.59 68.58 90)
		(unit 1)
		(exclude_from_sim no)
		(in_bom no)
		(on_board yes)
		(dnp no)
		(property "Reference" "TP78"
			(at 146.304 63.246 90)
			(effects
				(font
					(size 1.27 1.27)
				)
				(justify right)
			)
		)
		(property "Value" "TP_0.75mm_SMD"
			(at 152.4 58.42 0)
			(effects
				(font
					(size 1.27 1.27)
					(thickness 0.15)
				)
				(justify left bottom)
				(hide yes)
			)
		)
		(property "Footprint" "antmicro-footprints:TP_SMD_0.75mm"
			(at 154.94 58.42 0)
			(effects
				(font
					(size 1.27 1.27)
					(thickness 0.15)
				)
				(justify left bottom)
				(hide yes)
			)
		)
		(property "Datasheet" ""
			(at 161.29 50.8 0)
			(effects
				(font
					(size 1.27 1.27)
					(thickness 0.15)
				)
				(justify left bottom)
				(hide yes)
			)
		)
		(property "Description" "SMT test point"
			(at 148.59 68.58 0)
			(effects
				(font
					(size 1.27 1.27)
				)
				(hide yes)
			)
		)
		(property "MPN" ""
			(at 160.02 57.785 0)
			(effects
				(font
					(size 1.27 1.27)
					(thickness 0.15)
				)
				(justify left bottom)
				(hide yes)
			)
		)
		(property "Manufacturer" ""
			(at 154.94 57.785 0)
			(effects
				(font
					(size 1.27 1.27)
					(thickness 0.15)
				)
				(justify left bottom)
				(hide yes)
			)
		)
		(property "Author" "Antmicro"
			(at 157.48 58.42 0)
			(effects
				(font
					(size 1.27 1.27)
					(thickness 0.15)
				)
				(justify left bottom)
				(hide yes)
			)
		)
		(property "License" "Apache-2.0"
			(at 160.02 58.42 0)
			(effects
				(font
					(size 1.27 1.27)
					(thickness 0.15)
				)
				(justify left bottom)
				(hide yes)
			)
		)
		(pin "1"
		)
		(instances
			(project "jetson-agx-thor-baseboard"
				(path ""
					(reference "TP78")
					(unit 1)
				)
			)
		)
	)
	(symbol
		(lib_id "antmicroResistors0402:R_0R_0402")
		(at 227.33 241.3 0)
		(unit 1)
		(exclude_from_sim no)
		(in_bom yes)
		(on_board yes)
		(dnp no)
		(property "Reference" "R44"
			(at 225.425 240.03 0)
			(effects
				(font
					(size 1.27 1.27)
					(thickness 0.15)
				)
			)
		)
		(property "Value" "R_0R_0402"
			(at 247.65 254 0)
			(effects
				(font
					(size 1.27 1.27)
					(thickness 0.15)
				)
				(justify left bottom)
				(hide yes)
			)
		)
		(property "Footprint" "antmicro-footprints:R_0402_1005Metric"
			(at 247.65 256.54 0)
			(effects
				(font
					(size 1.27 1.27)
					(thickness 0.15)
				)
				(justify left bottom)
				(hide yes)
			)
		)
		(property "Datasheet" "https://industrial.panasonic.com/cdbs/www-data/pdf/RDA0000/AOA0000C301.pdf"
			(at 247.65 259.08 0)
			(effects
				(font
					(size 1.27 1.27)
					(thickness 0.15)
				)
				(justify left bottom)
				(hide yes)
			)
		)
		(property "Description" "SMD Chip Resistor, Jumper, 0 ohm, 100 mW, 0402 [1005 Metric], Thick Film, General Purpose"
			(at 227.33 241.3 0)
			(effects
				(font
					(size 1.27 1.27)
				)
				(hide yes)
			)
		)
		(property "MPN" "ERJ2GE0R00X"
			(at 247.65 261.62 0)
			(effects
				(font
					(size 1.27 1.27)
					(thickness 0.15)
				)
				(justify left bottom)
				(hide yes)
			)
		)
		(property "Manufacturer" "Panasonic"
			(at 247.65 264.16 0)
			(effects
				(font
					(size 1.27 1.27)
					(thickness 0.15)
				)
				(justify left bottom)
				(hide yes)
			)
		)
		(property "License" "Apache-2.0"
			(at 247.65 266.7 0)
			(effects
				(font
					(size 1.27 1.27)
					(thickness 0.15)
				)
				(justify left bottom)
				(hide yes)
			)
		)
		(property "Author" "Antmicro"
			(at 247.65 269.24 0)
			(effects
				(font
					(size 1.27 1.27)
					(thickness 0.15)
				)
				(justify left bottom)
				(hide yes)
			)
		)
		(property "Val" "0R"
			(at 233.68 240.03 0)
			(effects
				(font
					(size 1.27 1.27)
					(thickness 0.15)
				)
			)
		)
		(property "Tolerance" "~"
			(at 247.65 251.46 0)
			(effects
				(font
					(size 1.27 1.27)
				)
				(justify left bottom)
				(hide yes)
			)
		)
		(property "Current" "1A"
			(at 247.65 271.78 0)
			(effects
				(font
					(size 1.27 1.27)
					(thickness 0.15)
				)
				(justify left bottom)
				(hide yes)
			)
		)
		(pin "2"
		)
		(pin "1"
		)
		(instances
			(project "jetson-agx-thor-baseboard"
				(path ""
					(reference "R44")
					(unit 1)
				)
			)
		)
	)
	(symbol
		(lib_id "antmicroCapacitors0402:C_100n_0402")
		(at 78.74 110.49 270)
		(mirror x)
		(unit 1)
		(exclude_from_sim no)
		(in_bom yes)
		(on_board yes)
		(dnp no)
		(property "Reference" "C39"
			(at 78.232 106.172 90)
			(effects
				(font
					(size 1.27 1.27)
				)
				(justify right)
			)
		)
		(property "Value" "C_100n_0402"
			(at 68.58 90.17 0)
			(effects
				(font
					(size 1.27 1.27)
					(thickness 0.15)
				)
				(justify left bottom)
				(hide yes)
			)
		)
		(property "Footprint" "antmicro-footprints:C_0402_1005Metric"
			(at 66.04 90.17 0)
			(effects
				(font
					(size 1.27 1.27)
					(thickness 0.15)
				)
				(justify left bottom)
				(hide yes)
			)
		)
		(property "Datasheet" "https://www.murata.com/products/productdetail?partno=GRM155R61H104KE14%23"
			(at 63.5 90.17 0)
			(effects
				(font
					(size 1.27 1.27)
					(thickness 0.15)
				)
				(justify left bottom)
				(hide yes)
			)
		)
		(property "Description" "SMD Multilayer Ceramic Capacitor, 0.1 µF, 50 V, 0402 [1005 Metric], ± 10%, X5R, GRM Series"
			(at 78.74 110.49 0)
			(effects
				(font
					(size 1.27 1.27)
				)
				(hide yes)
			)
		)
		(property "Manufacturer" "Murata"
			(at 58.42 90.17 0)
			(effects
				(font
					(size 1.27 1.27)
					(thickness 0.15)
				)
				(justify left bottom)
				(hide yes)
			)
		)
		(property "MPN" "GRM155R61H104KE14D"
			(at 60.96 90.17 0)
			(effects
				(font
					(size 1.27 1.27)
					(thickness 0.15)
				)
				(justify left bottom)
				(hide yes)
			)
		)
		(property "Val" "100n"
			(at 78.232 109.728 90)
			(effects
				(font
					(size 1.27 1.27)
					(thickness 0.15)
				)
				(justify right)
			)
		)
		(property "License" "Apache-2.0"
			(at 55.88 90.17 0)
			(effects
				(font
					(size 1.27 1.27)
					(thickness 0.15)
				)
				(justify left bottom)
				(hide yes)
			)
		)
		(property "Author" "Antmicro"
			(at 53.34 90.17 0)
			(effects
				(font
					(size 1.27 1.27)
					(thickness 0.15)
				)
				(justify left bottom)
				(hide yes)
			)
		)
		(property "Voltage" "50V"
			(at 50.8 90.17 0)
			(effects
				(font
					(size 1.27 1.27)
				)
				(justify left bottom)
				(hide yes)
			)
		)
		(property "Dielectric" "X5R"
			(at 48.26 90.17 0)
			(effects
				(font
					(size 1.27 1.27)
				)
				(justify left bottom)
				(hide yes)
			)
		)
		(pin "1"
		)
		(pin "2"
		)
		(instances
			(project "jetson-agx-thor-baseboard"
				(path ""
					(reference "C39")
					(unit 1)
				)
			)
		)
	)
	(symbol
		(lib_id "antmicroTestPoints:TP_0.75mm_SMD")
		(at 269.24 76.2 0)
		(unit 1)
		(exclude_from_sim no)
		(in_bom no)
		(on_board yes)
		(dnp no)
		(property "Reference" "TP81"
			(at 274.32 76.2 0)
			(effects
				(font
					(size 1.27 1.27)
					(thickness 0.15)
				)
				(justify left)
			)
		)
		(property "Value" "TP_0.75mm_SMD"
			(at 279.4 80.01 0)
			(effects
				(font
					(size 1.27 1.27)
					(thickness 0.15)
				)
				(justify left bottom)
				(hide yes)
			)
		)
		(property "Footprint" "antmicro-footprints:TP_SMD_0.75mm"
			(at 279.4 82.55 0)
			(effects
				(font
					(size 1.27 1.27)
					(thickness 0.15)
				)
				(justify left bottom)
				(hide yes)
			)
		)
		(property "Datasheet" ""
			(at 287.02 88.9 0)
			(effects
				(font
					(size 1.27 1.27)
					(thickness 0.15)
				)
				(justify left bottom)
				(hide yes)
			)
		)
		(property "Description" "SMT test point"
			(at 269.24 76.2 0)
			(effects
				(font
					(size 1.27 1.27)
				)
				(hide yes)
			)
		)
		(property "MPN" ""
			(at 280.035 87.63 0)
			(effects
				(font
					(size 1.27 1.27)
					(thickness 0.15)
				)
				(justify left bottom)
				(hide yes)
			)
		)
		(property "Manufacturer" ""
			(at 280.035 82.55 0)
			(effects
				(font
					(size 1.27 1.27)
					(thickness 0.15)
				)
				(justify left bottom)
				(hide yes)
			)
		)
		(property "Author" "Antmicro"
			(at 279.4 85.09 0)
			(effects
				(font
					(size 1.27 1.27)
					(thickness 0.15)
				)
				(justify left bottom)
				(hide yes)
			)
		)
		(property "License" "Apache-2.0"
			(at 279.4 87.63 0)
			(effects
				(font
					(size 1.27 1.27)
					(thickness 0.15)
				)
				(justify left bottom)
				(hide yes)
			)
		)
		(pin "1"
		)
		(instances
			(project "jetson-agx-thor-baseboard"
				(path ""
					(reference "TP81")
					(unit 1)
				)
			)
		)
	)
	(symbol
		(lib_id "antmicropower:+3V3_AON")
		(at 290.83 156.21 0)
		(unit 1)
		(exclude_from_sim no)
		(in_bom yes)
		(on_board yes)
		(dnp no)
		(property "Reference" "#PWR0118"
			(at 290.83 160.02 0)
			(effects
				(font
					(size 1.27 1.27)
				)
				(hide yes)
			)
		)
		(property "Value" "+3V3_AON"
			(at 290.83 152.146 0)
			(effects
				(font
					(size 1.27 1.27)
				)
			)
		)
		(property "Footprint" ""
			(at 290.83 156.21 0)
			(effects
				(font
					(size 1.27 1.27)
				)
				(hide yes)
			)
		)
		(property "Datasheet" ""
			(at 290.83 156.21 0)
			(effects
				(font
					(size 1.27 1.27)
				)
				(hide yes)
			)
		)
		(property "Description" ""
			(at 290.83 156.21 0)
			(effects
				(font
					(size 1.27 1.27)
				)
				(hide yes)
			)
		)
		(pin "1"
		)
		(instances
			(project "jetson-agx-thor-baseboard"
				(path ""
					(reference "#PWR0118")
					(unit 1)
				)
			)
		)
	)
	(symbol
		(lib_id "antmicroTestPoints:TP_0.75mm_SMD")
		(at 194.31 74.93 0)
		(mirror y)
		(unit 1)
		(exclude_from_sim no)
		(in_bom no)
		(on_board yes)
		(dnp no)
		(fields_autoplaced yes)
		(property "Reference" "TP35"
			(at 189.23 74.93 0)
			(effects
				(font
					(size 1.27 1.27)
					(thickness 0.15)
				)
				(justify left)
			)
		)
		(property "Value" "TP_0.75mm_SMD"
			(at 184.15 78.74 0)
			(effects
				(font
					(size 1.27 1.27)
					(thickness 0.15)
				)
				(justify left bottom)
				(hide yes)
			)
		)
		(property "Footprint" "antmicro-footprints:TP_SMD_0.75mm"
			(at 184.15 81.28 0)
			(effects
				(font
					(size 1.27 1.27)
					(thickness 0.15)
				)
				(justify left bottom)
				(hide yes)
			)
		)
		(property "Datasheet" ""
			(at 176.53 87.63 0)
			(effects
				(font
					(size 1.27 1.27)
					(thickness 0.15)
				)
				(justify left bottom)
				(hide yes)
			)
		)
		(property "Description" "SMT test point"
			(at 194.31 74.93 0)
			(effects
				(font
					(size 1.27 1.27)
				)
				(hide yes)
			)
		)
		(property "MPN" ""
			(at 183.515 86.36 0)
			(effects
				(font
					(size 1.27 1.27)
					(thickness 0.15)
				)
				(justify left bottom)
				(hide yes)
			)
		)
		(property "Manufacturer" ""
			(at 183.515 81.28 0)
			(effects
				(font
					(size 1.27 1.27)
					(thickness 0.15)
				)
				(justify left bottom)
				(hide yes)
			)
		)
		(property "Author" "Antmicro"
			(at 184.15 83.82 0)
			(effects
				(font
					(size 1.27 1.27)
					(thickness 0.15)
				)
				(justify left bottom)
				(hide yes)
			)
		)
		(property "License" "Apache-2.0"
			(at 184.15 86.36 0)
			(effects
				(font
					(size 1.27 1.27)
					(thickness 0.15)
				)
				(justify left bottom)
				(hide yes)
			)
		)
		(pin "1"
		)
		(instances
			(project "jetson-agx-thor-baseboard"
				(path ""
					(reference "TP35")
					(unit 1)
				)
			)
		)
	)
	(symbol
		(lib_id "antmicroMechanicalParts:Spacer_Drill4.45mm_H4mm_9774040960R")
		(at 378.46 44.45 0)
		(unit 1)
		(exclude_from_sim no)
		(in_bom yes)
		(on_board yes)
		(dnp no)
		(property "Reference" "H6"
			(at 387.35 43.18 0)
			(effects
				(font
					(size 1.27 1.27)
					(thickness 0.15)
				)
				(justify left)
			)
		)
		(property "Value" "Spacer_Drill4.45mm_H4mm_9774040960R"
			(at 387.35 45.72 0)
			(effects
				(font
					(size 1.27 1.27)
					(thickness 0.15)
				)
				(justify left)
				(hide yes)
			)
		)
		(property "Footprint" "antmicro-footprints:Spacer_Drill4.45mm_H4mm_9774040960R"
			(at 401.32 52.07 0)
			(effects
				(font
					(size 1.27 1.27)
					(thickness 0.15)
				)
				(justify left bottom)
				(hide yes)
			)
		)
		(property "Datasheet" "https://www.we-online.com/components/products/datasheet/9774040960R.pdf"
			(at 401.32 54.61 0)
			(effects
				(font
					(size 1.27 1.27)
					(thickness 0.15)
				)
				(justify left bottom)
				(hide yes)
			)
		)
		(property "Description" "Spacer, SMT, Non Stop, Steel, Swage Round, 6 mm x 4 mm, 3.3 mm Internal, WA-SMST Series"
			(at 378.46 44.45 0)
			(effects
				(font
					(size 1.27 1.27)
				)
				(hide yes)
			)
		)
		(property "Manufacturer" "Würth Elektronik"
			(at 401.32 57.15 0)
			(effects
				(font
					(size 1.27 1.27)
					(thickness 0.15)
				)
				(justify left bottom)
				(hide yes)
			)
		)
		(property "MPN" "9774040960R"
			(at 387.35 46.482 0)
			(effects
				(font
					(size 1.27 1.27)
					(thickness 0.15)
				)
				(justify left bottom)
			)
		)
		(property "Author" "Antmicro"
			(at 401.32 62.23 0)
			(effects
				(font
					(size 1.27 1.27)
					(thickness 0.15)
				)
				(justify left bottom)
				(hide yes)
			)
		)
		(property "License" "Apache-2.0"
			(at 401.32 64.77 0)
			(effects
				(font
					(size 1.27 1.27)
					(thickness 0.15)
				)
				(justify left bottom)
				(hide yes)
			)
		)
		(pin "1"
		)
		(instances
			(project "jetson-agx-thor-baseboard"
				(path ""
					(reference "H6")
					(unit 1)
				)
			)
		)
	)
	(symbol
		(lib_id "antmicroTestPoints:TP_0.75mm_SMD")
		(at 262.89 81.28 0)
		(unit 1)
		(exclude_from_sim no)
		(in_bom no)
		(on_board yes)
		(dnp no)
		(fields_autoplaced yes)
		(property "Reference" "TP55"
			(at 267.97 81.28 0)
			(effects
				(font
					(size 1.27 1.27)
					(thickness 0.15)
				)
				(justify left)
			)
		)
		(property "Value" "TP_0.75mm_SMD"
			(at 273.05 85.09 0)
			(effects
				(font
					(size 1.27 1.27)
					(thickness 0.15)
				)
				(justify left bottom)
				(hide yes)
			)
		)
		(property "Footprint" "antmicro-footprints:TP_SMD_0.75mm"
			(at 273.05 87.63 0)
			(effects
				(font
					(size 1.27 1.27)
					(thickness 0.15)
				)
				(justify left bottom)
				(hide yes)
			)
		)
		(property "Datasheet" ""
			(at 280.67 93.98 0)
			(effects
				(font
					(size 1.27 1.27)
					(thickness 0.15)
				)
				(justify left bottom)
				(hide yes)
			)
		)
		(property "Description" "SMT test point"
			(at 262.89 81.28 0)
			(effects
				(font
					(size 1.27 1.27)
				)
				(hide yes)
			)
		)
		(property "MPN" ""
			(at 273.685 92.71 0)
			(effects
				(font
					(size 1.27 1.27)
					(thickness 0.15)
				)
				(justify left bottom)
				(hide yes)
			)
		)
		(property "Manufacturer" ""
			(at 273.685 87.63 0)
			(effects
				(font
					(size 1.27 1.27)
					(thickness 0.15)
				)
				(justify left bottom)
				(hide yes)
			)
		)
		(property "Author" "Antmicro"
			(at 273.05 90.17 0)
			(effects
				(font
					(size 1.27 1.27)
					(thickness 0.15)
				)
				(justify left bottom)
				(hide yes)
			)
		)
		(property "License" "Apache-2.0"
			(at 273.05 92.71 0)
			(effects
				(font
					(size 1.27 1.27)
					(thickness 0.15)
				)
				(justify left bottom)
				(hide yes)
			)
		)
		(pin "1"
		)
		(instances
			(project "jetson-agx-thor-baseboard"
				(path ""
					(reference "TP55")
					(unit 1)
				)
			)
		)
	)
	(symbol
		(lib_id "antmicropower:GND")
		(at 85.09 162.56 0)
		(unit 1)
		(exclude_from_sim no)
		(in_bom yes)
		(on_board yes)
		(dnp no)
		(property "Reference" "#PWR0670"
			(at 85.09 168.91 0)
			(effects
				(font
					(size 1.27 1.27)
				)
				(justify left bottom)
				(hide yes)
			)
		)
		(property "Value" "GND"
			(at 85.09 166.37 0)
			(effects
				(font
					(size 1.27 1.27)
					(thickness 0.15)
				)
			)
		)
		(property "Footprint" ""
			(at 93.98 170.18 0)
			(effects
				(font
					(size 1.27 1.27)
					(thickness 0.15)
				)
				(justify left bottom)
				(hide yes)
			)
		)
		(property "Datasheet" ""
			(at 93.98 175.26 0)
			(effects
				(font
					(size 1.27 1.27)
					(thickness 0.15)
				)
				(justify left bottom)
				(hide yes)
			)
		)
		(property "Description" ""
			(at 85.09 162.56 0)
			(effects
				(font
					(size 1.27 1.27)
				)
				(hide yes)
			)
		)
		(property "Author" "Antmicro"
			(at 93.98 170.18 0)
			(effects
				(font
					(size 1.27 1.27)
					(thickness 0.15)
				)
				(justify left bottom)
				(hide yes)
			)
		)
		(property "License" "Apache-2.0"
			(at 93.98 172.72 0)
			(effects
				(font
					(size 1.27 1.27)
					(thickness 0.15)
				)
				(justify left bottom)
				(hide yes)
			)
		)
		(pin "1"
		)
		(instances
			(project "jetson-agx-thor-baseboard"
				(path ""
					(reference "#PWR0670")
					(unit 1)
				)
			)
		)
	)
	(symbol
		(lib_id "antmicroTransistorsFETsMOSFETsSingle:DMG1012T-7")
		(at 48.26 48.26 0)
		(unit 1)
		(exclude_from_sim no)
		(in_bom yes)
		(on_board yes)
		(dnp no)
		(property "Reference" "Q6"
			(at 57.15 43.18 0)
			(effects
				(font
					(size 1.27 1.27)
					(thickness 0.15)
				)
				(justify left)
			)
		)
		(property "Value" "DMG1012T-7"
			(at 59.69 46.99 0)
			(effects
				(font
					(size 1.27 1.27)
					(thickness 0.15)
				)
				(justify left)
				(hide yes)
			)
		)
		(property "Footprint" "antmicro-footprints:SOT-523"
			(at 71.12 55.88 0)
			(effects
				(font
					(size 1.27 1.27)
					(thickness 0.15)
				)
				(justify left bottom)
				(hide yes)
			)
		)
		(property "Datasheet" "https://www.diodes.com/assets/Datasheets/ds31783.pdf"
			(at 71.12 58.42 0)
			(effects
				(font
					(size 1.27 1.27)
					(thickness 0.15)
				)
				(justify left bottom)
				(hide yes)
			)
		)
		(property "Description" "Power MOSFET, N Channel, 20 V, 630 mA, 0.3 ohm, SOT-523, Surface Mount"
			(at 48.26 48.26 0)
			(effects
				(font
					(size 1.27 1.27)
				)
				(hide yes)
			)
		)
		(property "MPN" "DMG1012T-7"
			(at 57.15 45.974 0)
			(effects
				(font
					(size 1.27 1.27)
					(thickness 0.15)
				)
				(justify left bottom)
			)
		)
		(property "Manufacturer" "Diodes Incorporated"
			(at 71.12 63.5 0)
			(effects
				(font
					(size 1.27 1.27)
					(thickness 0.15)
				)
				(justify left bottom)
				(hide yes)
			)
		)
		(property "Author" "Antmicro"
			(at 71.12 66.04 0)
			(effects
				(font
					(size 1.27 1.27)
					(thickness 0.15)
				)
				(justify left bottom)
				(hide yes)
			)
		)
		(property "License" "Apache-2.0"
			(at 71.12 68.58 0)
			(effects
				(font
					(size 1.27 1.27)
					(thickness 0.15)
				)
				(justify left bottom)
				(hide yes)
			)
		)
		(pin "1"
		)
		(pin "2"
		)
		(pin "3"
		)
		(instances
			(project "jetson-agx-thor-baseboard"
				(path ""
					(reference "Q6")
					(unit 1)
				)
			)
		)
	)
	(symbol
		(lib_id "antmicroCapacitors0603:C_22u_16V_0603")
		(at 115.57 38.1 90)
		(unit 1)
		(exclude_from_sim no)
		(in_bom yes)
		(on_board yes)
		(dnp no)
		(property "Reference" "C20"
			(at 118.11 34.2836 90)
			(effects
				(font
					(size 1.27 1.27)
					(thickness 0.15)
				)
				(justify right)
			)
		)
		(property "Value" "C_22u_16V_0603"
			(at 125.73 17.78 0)
			(effects
				(font
					(size 1.27 1.27)
					(thickness 0.15)
				)
				(justify left bottom)
				(hide yes)
			)
		)
		(property "Footprint" "antmicro-footprints:C_0603_1608Metric_EIA"
			(at 128.27 17.78 0)
			(effects
				(font
					(size 1.27 1.27)
					(thickness 0.15)
				)
				(justify left bottom)
				(hide yes)
			)
		)
		(property "Datasheet" "https://product.samsungsem.com/mlcc/CL10A226MO7JZN.do"
			(at 130.81 17.78 0)
			(effects
				(font
					(size 1.27 1.27)
					(thickness 0.15)
				)
				(justify left bottom)
				(hide yes)
			)
		)
		(property "Description" "SMD Multilayer Ceramic Capacitor"
			(at 115.57 38.1 0)
			(effects
				(font
					(size 1.27 1.27)
				)
				(hide yes)
			)
		)
		(property "MPN" "CL10A226MO7JZNC"
			(at 133.35 17.78 0)
			(effects
				(font
					(size 1.27 1.27)
					(thickness 0.15)
				)
				(justify left bottom)
				(hide yes)
			)
		)
		(property "Manufacturer" "Samsung Electro-Mechanics"
			(at 135.89 17.78 0)
			(effects
				(font
					(size 1.27 1.27)
					(thickness 0.15)
				)
				(justify left bottom)
				(hide yes)
			)
		)
		(property "License" "Apache-2.0"
			(at 138.43 17.78 0)
			(effects
				(font
					(size 1.27 1.27)
					(thickness 0.15)
				)
				(justify left bottom)
				(hide yes)
			)
		)
		(property "Author" "Antmicro"
			(at 140.97 17.78 0)
			(effects
				(font
					(size 1.27 1.27)
					(thickness 0.15)
				)
				(justify left bottom)
				(hide yes)
			)
		)
		(property "Val" "22u"
			(at 118.11 36.8236 90)
			(effects
				(font
					(size 1.27 1.27)
					(thickness 0.15)
				)
				(justify right)
			)
		)
		(property "Voltage" "16V"
			(at 143.51 17.78 0)
			(effects
				(font
					(size 1.27 1.27)
				)
				(justify left bottom)
				(hide yes)
			)
		)
		(property "Dielectric" "X7R"
			(at 146.05 17.78 0)
			(effects
				(font
					(size 1.27 1.27)
				)
				(justify left bottom)
				(hide yes)
			)
		)
		(property "Public" "False"
			(at 148.59 17.78 0)
			(effects
				(font
					(size 1.27 1.27)
				)
				(justify left bottom)
				(hide yes)
			)
		)
		(pin "1"
		)
		(pin "2"
		)
		(instances
			(project "jetson-agx-thor-baseboard"
				(path ""
					(reference "C20")
					(unit 1)
				)
			)
		)
	)
	(symbol
		(lib_id "antmicroTestPoints:TP_0.75mm_SMD")
		(at 251.46 97.79 0)
		(unit 1)
		(exclude_from_sim no)
		(in_bom no)
		(on_board yes)
		(dnp no)
		(fields_autoplaced yes)
		(property "Reference" "TP52"
			(at 256.54 97.79 0)
			(effects
				(font
					(size 1.27 1.27)
					(thickness 0.15)
				)
				(justify left)
			)
		)
		(property "Value" "TP_0.75mm_SMD"
			(at 261.62 101.6 0)
			(effects
				(font
					(size 1.27 1.27)
					(thickness 0.15)
				)
				(justify left bottom)
				(hide yes)
			)
		)
		(property "Footprint" "antmicro-footprints:TP_SMD_0.75mm"
			(at 261.62 104.14 0)
			(effects
				(font
					(size 1.27 1.27)
					(thickness 0.15)
				)
				(justify left bottom)
				(hide yes)
			)
		)
		(property "Datasheet" ""
			(at 269.24 110.49 0)
			(effects
				(font
					(size 1.27 1.27)
					(thickness 0.15)
				)
				(justify left bottom)
				(hide yes)
			)
		)
		(property "Description" "SMT test point"
			(at 251.46 97.79 0)
			(effects
				(font
					(size 1.27 1.27)
				)
				(hide yes)
			)
		)
		(property "MPN" ""
			(at 262.255 109.22 0)
			(effects
				(font
					(size 1.27 1.27)
					(thickness 0.15)
				)
				(justify left bottom)
				(hide yes)
			)
		)
		(property "Manufacturer" ""
			(at 262.255 104.14 0)
			(effects
				(font
					(size 1.27 1.27)
					(thickness 0.15)
				)
				(justify left bottom)
				(hide yes)
			)
		)
		(property "Author" "Antmicro"
			(at 261.62 106.68 0)
			(effects
				(font
					(size 1.27 1.27)
					(thickness 0.15)
				)
				(justify left bottom)
				(hide yes)
			)
		)
		(property "License" "Apache-2.0"
			(at 261.62 109.22 0)
			(effects
				(font
					(size 1.27 1.27)
					(thickness 0.15)
				)
				(justify left bottom)
				(hide yes)
			)
		)
		(pin "1"
		)
		(instances
			(project "jetson-agx-thor-baseboard"
				(path ""
					(reference "TP52")
					(unit 1)
				)
			)
		)
	)
	(symbol
		(lib_id "antmicroTestPoints:TP_0.75mm_SMD")
		(at 273.05 64.77 0)
		(unit 1)
		(exclude_from_sim no)
		(in_bom no)
		(on_board yes)
		(dnp no)
		(property "Reference" "TP79"
			(at 282.194 64.77 0)
			(effects
				(font
					(size 1.27 1.27)
				)
				(justify right)
			)
		)
		(property "Value" "TP_0.75mm_SMD"
			(at 283.21 68.58 0)
			(effects
				(font
					(size 1.27 1.27)
					(thickness 0.15)
				)
				(justify left bottom)
				(hide yes)
			)
		)
		(property "Footprint" "antmicro-footprints:TP_SMD_0.75mm"
			(at 283.21 71.12 0)
			(effects
				(font
					(size 1.27 1.27)
					(thickness 0.15)
				)
				(justify left bottom)
				(hide yes)
			)
		)
		(property "Datasheet" ""
			(at 290.83 77.47 0)
			(effects
				(font
					(size 1.27 1.27)
					(thickness 0.15)
				)
				(justify left bottom)
				(hide yes)
			)
		)
		(property "Description" "SMT test point"
			(at 273.05 64.77 0)
			(effects
				(font
					(size 1.27 1.27)
				)
				(hide yes)
			)
		)
		(property "MPN" ""
			(at 283.845 76.2 0)
			(effects
				(font
					(size 1.27 1.27)
					(thickness 0.15)
				)
				(justify left bottom)
				(hide yes)
			)
		)
		(property "Manufacturer" ""
			(at 283.845 71.12 0)
			(effects
				(font
					(size 1.27 1.27)
					(thickness 0.15)
				)
				(justify left bottom)
				(hide yes)
			)
		)
		(property "Author" "Antmicro"
			(at 283.21 73.66 0)
			(effects
				(font
					(size 1.27 1.27)
					(thickness 0.15)
				)
				(justify left bottom)
				(hide yes)
			)
		)
		(property "License" "Apache-2.0"
			(at 283.21 76.2 0)
			(effects
				(font
					(size 1.27 1.27)
					(thickness 0.15)
				)
				(justify left bottom)
				(hide yes)
			)
		)
		(pin "1"
		)
		(instances
			(project "jetson-agx-thor-baseboard"
				(path ""
					(reference "TP79")
					(unit 1)
				)
			)
		)
	)
	(symbol
		(lib_id "antmicropower:GND")
		(at 323.85 182.88 0)
		(unit 1)
		(exclude_from_sim no)
		(in_bom yes)
		(on_board yes)
		(dnp no)
		(property "Reference" "#PWR0660"
			(at 323.85 189.23 0)
			(effects
				(font
					(size 1.27 1.27)
				)
				(justify left bottom)
				(hide yes)
			)
		)
		(property "Value" "GND"
			(at 323.85 186.69 0)
			(effects
				(font
					(size 1.27 1.27)
					(thickness 0.15)
				)
			)
		)
		(property "Footprint" ""
			(at 332.74 190.5 0)
			(effects
				(font
					(size 1.27 1.27)
					(thickness 0.15)
				)
				(justify left bottom)
				(hide yes)
			)
		)
		(property "Datasheet" ""
			(at 332.74 195.58 0)
			(effects
				(font
					(size 1.27 1.27)
					(thickness 0.15)
				)
				(justify left bottom)
				(hide yes)
			)
		)
		(property "Description" ""
			(at 323.85 182.88 0)
			(effects
				(font
					(size 1.27 1.27)
				)
				(hide yes)
			)
		)
		(property "Author" "Antmicro"
			(at 332.74 190.5 0)
			(effects
				(font
					(size 1.27 1.27)
					(thickness 0.15)
				)
				(justify left bottom)
				(hide yes)
			)
		)
		(property "License" "Apache-2.0"
			(at 332.74 193.04 0)
			(effects
				(font
					(size 1.27 1.27)
					(thickness 0.15)
				)
				(justify left bottom)
				(hide yes)
			)
		)
		(pin "1"
		)
		(instances
			(project "jetson-agx-thor-baseboard"
				(path ""
					(reference "#PWR0660")
					(unit 1)
				)
			)
		)
	)
	(symbol
		(lib_id "antmicroResistors0402:R_100k_0402")
		(at 118.11 227.33 90)
		(unit 1)
		(exclude_from_sim no)
		(in_bom no)
		(on_board yes)
		(dnp yes)
		(fields_autoplaced yes)
		(property "Reference" "R308"
			(at 115.57 223.52 90)
			(effects
				(font
					(size 1.27 1.27)
					(thickness 0.15)
				)
				(justify left)
			)
		)
		(property "Value" "R_100k_0402"
			(at 130.81 207.01 0)
			(effects
				(font
					(size 1.27 1.27)
					(thickness 0.15)
				)
				(justify left bottom)
				(hide yes)
			)
		)
		(property "Footprint" "antmicro-footprints:R_0402_1005Metric"
			(at 133.35 207.01 0)
			(effects
				(font
					(size 1.27 1.27)
					(thickness 0.15)
				)
				(justify left bottom)
				(hide yes)
			)
		)
		(property "Datasheet" "https://www.bourns.com/docs/product-datasheets/cr.pdf"
			(at 135.89 207.01 0)
			(effects
				(font
					(size 1.27 1.27)
					(thickness 0.15)
				)
				(justify left bottom)
				(hide yes)
			)
		)
		(property "Description" "SMD Chip Resistor, 100 kohm, ± 1%, 62.5 mW, 0402 [1005 Metric], Thick Film, General Purpose"
			(at 118.11 227.33 0)
			(effects
				(font
					(size 1.27 1.27)
				)
				(hide yes)
			)
		)
		(property "MPN" "CR0402-FX-1003GLF"
			(at 138.43 207.01 0)
			(effects
				(font
					(size 1.27 1.27)
					(thickness 0.15)
				)
				(justify left bottom)
				(hide yes)
			)
		)
		(property "Manufacturer" "Bourns"
			(at 140.97 207.01 0)
			(effects
				(font
					(size 1.27 1.27)
					(thickness 0.15)
				)
				(justify left bottom)
				(hide yes)
			)
		)
		(property "License" "Apache-2.0"
			(at 143.51 207.01 0)
			(effects
				(font
					(size 1.27 1.27)
					(thickness 0.15)
				)
				(justify left bottom)
				(hide yes)
			)
		)
		(property "Author" "Antmicro"
			(at 146.05 207.01 0)
			(effects
				(font
					(size 1.27 1.27)
					(thickness 0.15)
				)
				(justify left bottom)
				(hide yes)
			)
		)
		(property "Val" "100k"
			(at 115.57 226.06 90)
			(effects
				(font
					(size 1.27 1.27)
					(thickness 0.15)
				)
				(justify left)
			)
		)
		(property "Tolerance" "1%"
			(at 128.27 207.01 0)
			(effects
				(font
					(size 1.27 1.27)
				)
				(justify left bottom)
				(hide yes)
			)
		)
		(property "Public" "False"
			(at 148.59 207.01 0)
			(effects
				(font
					(size 1.27 1.27)
				)
				(justify left bottom)
				(hide yes)
			)
		)
		(pin "2"
		)
		(pin "1"
		)
		(instances
			(project "jetson-agx-thor-baseboard"
				(path ""
					(reference "R308")
					(unit 1)
				)
			)
		)
	)
	(symbol
		(lib_id "antmicroCapacitors0402:C_1u_25V_0402")
		(at 204.47 38.1 90)
		(unit 1)
		(exclude_from_sim no)
		(in_bom yes)
		(on_board yes)
		(dnp no)
		(property "Reference" "C365"
			(at 206.375 33.02 90)
			(effects
				(font
					(size 1.27 1.27)
					(thickness 0.15)
				)
				(justify right)
			)
		)
		(property "Value" "C_1u_25V_0402"
			(at 214.63 17.78 0)
			(effects
				(font
					(size 1.27 1.27)
					(thickness 0.15)
				)
				(justify left bottom)
				(hide yes)
			)
		)
		(property "Footprint" "antmicro-footprints:C_0402_1005Metric"
			(at 217.17 17.78 0)
			(effects
				(font
					(size 1.27 1.27)
					(thickness 0.15)
				)
				(justify left bottom)
				(hide yes)
			)
		)
		(property "Datasheet" "https://www.murata.com/products/productdetail?partno=GRM155R61E105KE11%23"
			(at 219.71 17.78 0)
			(effects
				(font
					(size 1.27 1.27)
					(thickness 0.15)
				)
				(justify left bottom)
				(hide yes)
			)
		)
		(property "Description" "SMD Multilayer Ceramic Capacitor, 1 µF, 25 V, 0402 [1005 Metric], ± 10%, X5R, GRM Series"
			(at 237.49 17.78 0)
			(effects
				(font
					(size 1.27 1.27)
				)
				(justify left bottom)
				(hide yes)
			)
		)
		(property "MPN" "GRM155R61E105KE11J"
			(at 222.25 17.78 0)
			(effects
				(font
					(size 1.27 1.27)
					(thickness 0.15)
				)
				(justify left bottom)
				(hide yes)
			)
		)
		(property "Manufacturer" "Murata"
			(at 224.79 17.78 0)
			(effects
				(font
					(size 1.27 1.27)
					(thickness 0.15)
				)
				(justify left bottom)
				(hide yes)
			)
		)
		(property "License" "Apache-2.0"
			(at 227.33 17.78 0)
			(effects
				(font
					(size 1.27 1.27)
					(thickness 0.15)
				)
				(justify left bottom)
				(hide yes)
			)
		)
		(property "Author" "Antmicro"
			(at 229.87 17.78 0)
			(effects
				(font
					(size 1.27 1.27)
					(thickness 0.15)
				)
				(justify left bottom)
				(hide yes)
			)
		)
		(property "Val" "1u"
			(at 206.375 35.56 90)
			(effects
				(font
					(size 1.27 1.27)
					(thickness 0.15)
				)
				(justify right)
			)
		)
		(property "Voltage" "25V"
			(at 206.375 38.0999 90)
			(effects
				(font
					(size 1.27 1.27)
				)
				(justify right)
			)
		)
		(property "Dielectric" "X5R"
			(at 234.95 17.78 0)
			(effects
				(font
					(size 1.27 1.27)
				)
				(justify left bottom)
				(hide yes)
			)
		)
		(pin "1"
		)
		(pin "2"
		)
		(instances
			(project "jetson-agx-thor-baseboard"
				(path ""
					(reference "C365")
					(unit 1)
				)
			)
		)
	)
	(symbol
		(lib_id "antmicroTestPoints:TP_0.75mm_SMD")
		(at 251.46 88.9 0)
		(unit 1)
		(exclude_from_sim no)
		(in_bom no)
		(on_board yes)
		(dnp no)
		(fields_autoplaced yes)
		(property "Reference" "TP50"
			(at 256.54 88.9 0)
			(effects
				(font
					(size 1.27 1.27)
					(thickness 0.15)
				)
				(justify left)
			)
		)
		(property "Value" "TP_0.75mm_SMD"
			(at 261.62 92.71 0)
			(effects
				(font
					(size 1.27 1.27)
					(thickness 0.15)
				)
				(justify left bottom)
				(hide yes)
			)
		)
		(property "Footprint" "antmicro-footprints:TP_SMD_0.75mm"
			(at 261.62 95.25 0)
			(effects
				(font
					(size 1.27 1.27)
					(thickness 0.15)
				)
				(justify left bottom)
				(hide yes)
			)
		)
		(property "Datasheet" ""
			(at 269.24 101.6 0)
			(effects
				(font
					(size 1.27 1.27)
					(thickness 0.15)
				)
				(justify left bottom)
				(hide yes)
			)
		)
		(property "Description" "SMT test point"
			(at 251.46 88.9 0)
			(effects
				(font
					(size 1.27 1.27)
				)
				(hide yes)
			)
		)
		(property "MPN" ""
			(at 262.255 100.33 0)
			(effects
				(font
					(size 1.27 1.27)
					(thickness 0.15)
				)
				(justify left bottom)
				(hide yes)
			)
		)
		(property "Manufacturer" ""
			(at 262.255 95.25 0)
			(effects
				(font
					(size 1.27 1.27)
					(thickness 0.15)
				)
				(justify left bottom)
				(hide yes)
			)
		)
		(property "Author" "Antmicro"
			(at 261.62 97.79 0)
			(effects
				(font
					(size 1.27 1.27)
					(thickness 0.15)
				)
				(justify left bottom)
				(hide yes)
			)
		)
		(property "License" "Apache-2.0"
			(at 261.62 100.33 0)
			(effects
				(font
					(size 1.27 1.27)
					(thickness 0.15)
				)
				(justify left bottom)
				(hide yes)
			)
		)
		(pin "1"
		)
		(instances
			(project "jetson-agx-thor-baseboard"
				(path ""
					(reference "TP50")
					(unit 1)
				)
			)
		)
	)
	(symbol
		(lib_id "antmicropower:PWR_FLAG")
		(at 154.94 72.39 0)
		(unit 1)
		(exclude_from_sim no)
		(in_bom yes)
		(on_board yes)
		(dnp no)
		(property "Reference" "#FLG06"
			(at 154.94 70.485 0)
			(effects
				(font
					(size 1.27 1.27)
				)
				(hide yes)
			)
		)
		(property "Value" "PWR_FLAG"
			(at 154.94 68.58 0)
			(effects
				(font
					(size 1.27 1.27)
				)
			)
		)
		(property "Footprint" ""
			(at 154.94 72.39 0)
			(effects
				(font
					(size 1.27 1.27)
				)
				(hide yes)
			)
		)
		(property "Datasheet" ""
			(at 154.94 72.39 0)
			(effects
				(font
					(size 1.27 1.27)
				)
				(hide yes)
			)
		)
		(property "Description" ""
			(at 154.94 72.39 0)
			(effects
				(font
					(size 1.27 1.27)
				)
				(hide yes)
			)
		)
		(pin "1"
		)
		(instances
			(project "jetson-agx-thor-baseboard"
				(path ""
					(reference "#FLG06")
					(unit 1)
				)
			)
		)
	)
	(symbol
		(lib_id "antmicropower:GND")
		(at 71.12 115.57 0)
		(mirror y)
		(unit 1)
		(exclude_from_sim no)
		(in_bom yes)
		(on_board yes)
		(dnp no)
		(property "Reference" "#PWR086"
			(at 71.12 121.92 0)
			(effects
				(font
					(size 1.27 1.27)
				)
				(justify left bottom)
				(hide yes)
			)
		)
		(property "Value" "GND"
			(at 71.12 119.38 0)
			(effects
				(font
					(size 1.27 1.27)
					(thickness 0.15)
				)
			)
		)
		(property "Footprint" ""
			(at 62.23 123.19 0)
			(effects
				(font
					(size 1.27 1.27)
					(thickness 0.15)
				)
				(justify left bottom)
				(hide yes)
			)
		)
		(property "Datasheet" ""
			(at 62.23 128.27 0)
			(effects
				(font
					(size 1.27 1.27)
					(thickness 0.15)
				)
				(justify left bottom)
				(hide yes)
			)
		)
		(property "Description" ""
			(at 71.12 115.57 0)
			(effects
				(font
					(size 1.27 1.27)
				)
				(hide yes)
			)
		)
		(property "Author" "Antmicro"
			(at 62.23 123.19 0)
			(effects
				(font
					(size 1.27 1.27)
					(thickness 0.15)
				)
				(justify left bottom)
				(hide yes)
			)
		)
		(property "License" "Apache-2.0"
			(at 62.23 125.73 0)
			(effects
				(font
					(size 1.27 1.27)
					(thickness 0.15)
				)
				(justify left bottom)
				(hide yes)
			)
		)
		(pin "1"
		)
		(instances
			(project "jetson-agx-thor-baseboard"
				(path ""
					(reference "#PWR086")
					(unit 1)
				)
			)
		)
	)
	(symbol
		(lib_id "antmicroCapacitors0402:C_1u_25V_0402")
		(at 92.71 256.54 90)
		(unit 1)
		(exclude_from_sim no)
		(in_bom yes)
		(on_board yes)
		(dnp no)
		(fields_autoplaced yes)
		(property "Reference" "C226"
			(at 95.25 252.7236 90)
			(effects
				(font
					(size 1.27 1.27)
					(thickness 0.15)
				)
				(justify right)
			)
		)
		(property "Value" "C_1u_25V_0402"
			(at 102.87 236.22 0)
			(effects
				(font
					(size 1.27 1.27)
					(thickness 0.15)
				)
				(justify left bottom)
				(hide yes)
			)
		)
		(property "Footprint" "antmicro-footprints:C_0402_1005Metric"
			(at 105.41 236.22 0)
			(effects
				(font
					(size 1.27 1.27)
					(thickness 0.15)
				)
				(justify left bottom)
				(hide yes)
			)
		)
		(property "Datasheet" "https://www.murata.com/products/productdetail?partno=GRM155R61E105KE11%23"
			(at 107.95 236.22 0)
			(effects
				(font
					(size 1.27 1.27)
					(thickness 0.15)
				)
				(justify left bottom)
				(hide yes)
			)
		)
		(property "Description" "SMD Multilayer Ceramic Capacitor, 1 µF, 25 V, 0402 [1005 Metric], ± 10%, X5R, GRM Series"
			(at 92.71 256.54 0)
			(effects
				(font
					(size 1.27 1.27)
				)
				(hide yes)
			)
		)
		(property "MPN" "GRM155R61E105KE11J"
			(at 110.49 236.22 0)
			(effects
				(font
					(size 1.27 1.27)
					(thickness 0.15)
				)
				(justify left bottom)
				(hide yes)
			)
		)
		(property "Manufacturer" "Murata"
			(at 113.03 236.22 0)
			(effects
				(font
					(size 1.27 1.27)
					(thickness 0.15)
				)
				(justify left bottom)
				(hide yes)
			)
		)
		(property "License" "Apache-2.0"
			(at 115.57 236.22 0)
			(effects
				(font
					(size 1.27 1.27)
					(thickness 0.15)
				)
				(justify left bottom)
				(hide yes)
			)
		)
		(property "Author" "Antmicro"
			(at 118.11 236.22 0)
			(effects
				(font
					(size 1.27 1.27)
					(thickness 0.15)
				)
				(justify left bottom)
				(hide yes)
			)
		)
		(property "Val" "1u"
			(at 95.25 255.2636 90)
			(effects
				(font
					(size 1.27 1.27)
					(thickness 0.15)
				)
				(justify right)
			)
		)
		(property "Voltage" "25V"
			(at 120.65 236.22 0)
			(effects
				(font
					(size 1.27 1.27)
				)
				(justify left bottom)
				(hide yes)
			)
		)
		(property "Dielectric" "X5R"
			(at 123.19 236.22 0)
			(effects
				(font
					(size 1.27 1.27)
				)
				(justify left bottom)
				(hide yes)
			)
		)
		(pin "2"
		)
		(pin "1"
		)
		(instances
			(project "jetson-agx-thor-baseboard"
				(path ""
					(reference "C226")
					(unit 1)
				)
			)
		)
	)
	(symbol
		(lib_id "antmicropower:GND")
		(at 58.42 259.08 0)
		(unit 1)
		(exclude_from_sim no)
		(in_bom yes)
		(on_board yes)
		(dnp no)
		(property "Reference" "#PWR0559"
			(at 58.42 265.43 0)
			(effects
				(font
					(size 1.27 1.27)
				)
				(justify left bottom)
				(hide yes)
			)
		)
		(property "Value" "GND"
			(at 58.42 262.89 0)
			(effects
				(font
					(size 1.27 1.27)
					(thickness 0.15)
				)
			)
		)
		(property "Footprint" ""
			(at 67.31 266.7 0)
			(effects
				(font
					(size 1.27 1.27)
					(thickness 0.15)
				)
				(justify left bottom)
				(hide yes)
			)
		)
		(property "Datasheet" ""
			(at 67.31 271.78 0)
			(effects
				(font
					(size 1.27 1.27)
					(thickness 0.15)
				)
				(justify left bottom)
				(hide yes)
			)
		)
		(property "Description" ""
			(at 58.42 259.08 0)
			(effects
				(font
					(size 1.27 1.27)
				)
				(hide yes)
			)
		)
		(property "Author" "Antmicro"
			(at 67.31 266.7 0)
			(effects
				(font
					(size 1.27 1.27)
					(thickness 0.15)
				)
				(justify left bottom)
				(hide yes)
			)
		)
		(property "License" "Apache-2.0"
			(at 67.31 269.24 0)
			(effects
				(font
					(size 1.27 1.27)
					(thickness 0.15)
				)
				(justify left bottom)
				(hide yes)
			)
		)
		(pin "1"
		)
		(instances
			(project "jetson-agx-thor-baseboard"
				(path ""
					(reference "#PWR0559")
					(unit 1)
				)
			)
		)
	)
	(symbol
		(lib_id "antmicroTransistorsFETsMOSFETsSingle:DMG1012T-7")
		(at 300.99 177.8 0)
		(unit 1)
		(exclude_from_sim no)
		(in_bom yes)
		(on_board yes)
		(dnp no)
		(property "Reference" "Q8"
			(at 311.15 181.102 90)
			(effects
				(font
					(size 1.27 1.27)
					(thickness 0.15)
				)
				(justify left)
			)
		)
		(property "Value" "DMG1012T-7"
			(at 323.85 194.31 0)
			(effects
				(font
					(size 1.27 1.27)
					(thickness 0.15)
				)
				(justify left bottom)
				(hide yes)
			)
		)
		(property "Footprint" "antmicro-footprints:SOT-523"
			(at 323.85 189.23 0)
			(effects
				(font
					(size 1.27 1.27)
					(thickness 0.15)
				)
				(justify left bottom)
				(hide yes)
			)
		)
		(property "Datasheet" "https://www.diodes.com/assets/Datasheets/ds31783.pdf"
			(at 323.85 191.77 0)
			(effects
				(font
					(size 1.27 1.27)
					(thickness 0.15)
				)
				(justify left bottom)
				(hide yes)
			)
		)
		(property "Description" "Power MOSFET, N Channel, 20 V, 630 mA, 0.3 ohm, SOT-523, Surface Mount"
			(at 360.172 203.708 0)
			(effects
				(font
					(size 1.27 1.27)
				)
				(hide yes)
			)
		)
		(property "MPN" "DMG1012T-7"
			(at 313.69 181.102 90)
			(effects
				(font
					(size 1.27 1.27)
					(thickness 0.15)
				)
				(justify left)
			)
		)
		(property "Manufacturer" "Diodes Incorporated"
			(at 323.85 196.85 0)
			(effects
				(font
					(size 1.27 1.27)
					(thickness 0.15)
				)
				(justify left bottom)
				(hide yes)
			)
		)
		(property "Author" "Antmicro"
			(at 323.85 199.39 0)
			(effects
				(font
					(size 1.27 1.27)
					(thickness 0.15)
				)
				(justify left bottom)
				(hide yes)
			)
		)
		(property "License" "Apache-2.0"
			(at 323.85 201.93 0)
			(effects
				(font
					(size 1.27 1.27)
					(thickness 0.15)
				)
				(justify left bottom)
				(hide yes)
			)
		)
		(pin "1"
		)
		(pin "3"
		)
		(pin "2"
		)
		(instances
			(project "jetson-agx-thor-baseboard"
				(path ""
					(reference "Q8")
					(unit 1)
				)
			)
		)
	)
	(symbol
		(lib_id "antmicropower:GND")
		(at 344.17 242.57 0)
		(unit 1)
		(exclude_from_sim no)
		(in_bom yes)
		(on_board yes)
		(dnp no)
		(property "Reference" "#PWR0666"
			(at 344.17 248.92 0)
			(effects
				(font
					(size 1.27 1.27)
				)
				(justify left bottom)
				(hide yes)
			)
		)
		(property "Value" "GND"
			(at 344.17 246.38 0)
			(effects
				(font
					(size 1.27 1.27)
					(thickness 0.15)
				)
			)
		)
		(property "Footprint" ""
			(at 353.06 250.19 0)
			(effects
				(font
					(size 1.27 1.27)
					(thickness 0.15)
				)
				(justify left bottom)
				(hide yes)
			)
		)
		(property "Datasheet" ""
			(at 353.06 255.27 0)
			(effects
				(font
					(size 1.27 1.27)
					(thickness 0.15)
				)
				(justify left bottom)
				(hide yes)
			)
		)
		(property "Description" ""
			(at 344.17 242.57 0)
			(effects
				(font
					(size 1.27 1.27)
				)
				(hide yes)
			)
		)
		(property "Author" "Antmicro"
			(at 353.06 250.19 0)
			(effects
				(font
					(size 1.27 1.27)
					(thickness 0.15)
				)
				(justify left bottom)
				(hide yes)
			)
		)
		(property "License" "Apache-2.0"
			(at 353.06 252.73 0)
			(effects
				(font
					(size 1.27 1.27)
					(thickness 0.15)
				)
				(justify left bottom)
				(hide yes)
			)
		)
		(pin "1"
		)
		(instances
			(project "jetson-agx-thor-baseboard"
				(path ""
					(reference "#PWR0666")
					(unit 1)
				)
			)
		)
	)
	(symbol
		(lib_id "antmicroMechanicalParts:Spacer_Drill4.45mm_H4mm_9774040960R")
		(at 378.46 36.83 0)
		(unit 1)
		(exclude_from_sim no)
		(in_bom yes)
		(on_board yes)
		(dnp no)
		(property "Reference" "H5"
			(at 387.35 35.56 0)
			(effects
				(font
					(size 1.27 1.27)
					(thickness 0.15)
				)
				(justify left)
			)
		)
		(property "Value" "Spacer_Drill4.45mm_H4mm_9774040960R"
			(at 387.35 38.1 0)
			(effects
				(font
					(size 1.27 1.27)
					(thickness 0.15)
				)
				(justify left)
				(hide yes)
			)
		)
		(property "Footprint" "antmicro-footprints:Spacer_Drill4.45mm_H4mm_9774040960R"
			(at 401.32 44.45 0)
			(effects
				(font
					(size 1.27 1.27)
					(thickness 0.15)
				)
				(justify left bottom)
				(hide yes)
			)
		)
		(property "Datasheet" "https://www.we-online.com/components/products/datasheet/9774040960R.pdf"
			(at 401.32 46.99 0)
			(effects
				(font
					(size 1.27 1.27)
					(thickness 0.15)
				)
				(justify left bottom)
				(hide yes)
			)
		)
		(property "Description" "Spacer, SMT, Non Stop, Steel, Swage Round, 6 mm x 4 mm, 3.3 mm Internal, WA-SMST Series"
			(at 378.46 36.83 0)
			(effects
				(font
					(size 1.27 1.27)
				)
				(hide yes)
			)
		)
		(property "Manufacturer" "Würth Elektronik"
			(at 401.32 49.53 0)
			(effects
				(font
					(size 1.27 1.27)
					(thickness 0.15)
				)
				(justify left bottom)
				(hide yes)
			)
		)
		(property "MPN" "9774040960R"
			(at 387.35 38.862 0)
			(effects
				(font
					(size 1.27 1.27)
					(thickness 0.15)
				)
				(justify left bottom)
			)
		)
		(property "Author" "Antmicro"
			(at 401.32 54.61 0)
			(effects
				(font
					(size 1.27 1.27)
					(thickness 0.15)
				)
				(justify left bottom)
				(hide yes)
			)
		)
		(property "License" "Apache-2.0"
			(at 401.32 57.15 0)
			(effects
				(font
					(size 1.27 1.27)
					(thickness 0.15)
				)
				(justify left bottom)
				(hide yes)
			)
		)
		(pin "1"
		)
		(instances
			(project "jetson-agx-thor-baseboard"
				(path ""
					(reference "H5")
					(unit 1)
				)
			)
		)
	)
	(symbol
		(lib_id "antmicropower:+3V3_AON")
		(at 163.83 55.88 0)
		(unit 1)
		(exclude_from_sim no)
		(in_bom yes)
		(on_board yes)
		(dnp no)
		(property "Reference" "#PWR049"
			(at 163.83 59.69 0)
			(effects
				(font
					(size 1.27 1.27)
				)
				(hide yes)
			)
		)
		(property "Value" "+3V3_AON"
			(at 163.83 52.07 0)
			(effects
				(font
					(size 1.27 1.27)
				)
			)
		)
		(property "Footprint" ""
			(at 163.83 55.88 0)
			(effects
				(font
					(size 1.27 1.27)
				)
				(hide yes)
			)
		)
		(property "Datasheet" ""
			(at 163.83 55.88 0)
			(effects
				(font
					(size 1.27 1.27)
				)
				(hide yes)
			)
		)
		(property "Description" ""
			(at 163.83 55.88 0)
			(effects
				(font
					(size 1.27 1.27)
				)
				(hide yes)
			)
		)
		(pin "1"
		)
		(instances
			(project "jetson-agx-thor-baseboard"
				(path ""
					(reference "#PWR049")
					(unit 1)
				)
			)
		)
	)
	(symbol
		(lib_id "antmicropower:GND")
		(at 193.04 118.11 0)
		(unit 1)
		(exclude_from_sim no)
		(in_bom yes)
		(on_board yes)
		(dnp no)
		(fields_autoplaced yes)
		(property "Reference" "#PWR041"
			(at 201.93 120.65 0)
			(effects
				(font
					(size 1.27 1.27)
					(thickness 0.15)
				)
				(justify left bottom)
				(hide yes)
			)
		)
		(property "Value" "GND"
			(at 193.04 123.19 0)
			(effects
				(font
					(size 1.27 1.27)
					(thickness 0.15)
				)
			)
		)
		(property "Footprint" ""
			(at 201.93 125.73 0)
			(effects
				(font
					(size 1.27 1.27)
					(thickness 0.15)
				)
				(justify left bottom)
				(hide yes)
			)
		)
		(property "Datasheet" ""
			(at 201.93 130.81 0)
			(effects
				(font
					(size 1.27 1.27)
					(thickness 0.15)
				)
				(justify left bottom)
				(hide yes)
			)
		)
		(property "Description" ""
			(at 193.04 118.11 0)
			(effects
				(font
					(size 1.27 1.27)
				)
				(hide yes)
			)
		)
		(property "Author" "Antmicro"
			(at 201.93 125.73 0)
			(effects
				(font
					(size 1.27 1.27)
					(thickness 0.15)
				)
				(justify left bottom)
				(hide yes)
			)
		)
		(property "License" "Apache-2.0"
			(at 201.93 128.27 0)
			(effects
				(font
					(size 1.27 1.27)
					(thickness 0.15)
				)
				(justify left bottom)
				(hide yes)
			)
		)
		(pin "1"
		)
		(instances
			(project "jetson-agx-thor-baseboard"
				(path ""
					(reference "#PWR041")
					(unit 1)
				)
			)
		)
	)
	(symbol
		(lib_id "antmicroDiodesRectifiersSingle:RB521S30T1G")
		(at 143.51 72.39 180)
		(unit 1)
		(exclude_from_sim no)
		(in_bom yes)
		(on_board yes)
		(dnp no)
		(property "Reference" "D1"
			(at 140.97 67.31 0)
			(effects
				(font
					(size 1.27 1.27)
				)
			)
		)
		(property "Value" "RB521S30T1G"
			(at 120.65 57.15 0)
			(effects
				(font
					(size 1.27 1.27)
					(thickness 0.15)
				)
				(justify left bottom)
				(hide yes)
			)
		)
		(property "Footprint" "antmicro-footprints:SOD-523"
			(at 120.65 62.23 0)
			(effects
				(font
					(size 1.27 1.27)
					(thickness 0.15)
				)
				(justify left bottom)
				(hide yes)
			)
		)
		(property "Datasheet" "https://www.onsemi.com/pdf/datasheet/rb521s30t1-d.pdf"
			(at 120.65 59.69 0)
			(effects
				(font
					(size 1.27 1.27)
					(thickness 0.15)
				)
				(justify left bottom)
				(hide yes)
			)
		)
		(property "Description" "Small Signal Schottky Diode, Single, 30 V, 200 mA, 500 mV, 1 A, 125 °C"
			(at 143.51 72.39 0)
			(effects
				(font
					(size 1.27 1.27)
				)
				(hide yes)
			)
		)
		(property "MPN" "RB521S30T1G"
			(at 140.97 69.85 0)
			(effects
				(font
					(size 1.27 1.27)
					(thickness 0.15)
				)
			)
		)
		(property "Manufacturer" "ON Semiconductor"
			(at 120.65 54.61 0)
			(effects
				(font
					(size 1.27 1.27)
					(thickness 0.15)
				)
				(justify left bottom)
				(hide yes)
			)
		)
		(property "Author" "Antmicro"
			(at 120.65 52.07 0)
			(effects
				(font
					(size 1.27 1.27)
					(thickness 0.15)
				)
				(justify left bottom)
				(hide yes)
			)
		)
		(property "License" "Apache-2.0"
			(at 120.65 49.53 0)
			(effects
				(font
					(size 1.27 1.27)
					(thickness 0.15)
				)
				(justify left bottom)
				(hide yes)
			)
		)
		(pin "1"
		)
		(pin "2"
		)
		(instances
			(project "jetson-agx-thor-baseboard"
				(path ""
					(reference "D1")
					(unit 1)
				)
			)
		)
	)
	(symbol
		(lib_id "antmicroCapacitors0402:C_100n_0402")
		(at 60.96 170.18 90)
		(unit 1)
		(exclude_from_sim no)
		(in_bom yes)
		(on_board yes)
		(dnp no)
		(fields_autoplaced yes)
		(property "Reference" "C40"
			(at 63.5 166.3636 90)
			(effects
				(font
					(size 1.27 1.27)
					(thickness 0.15)
				)
				(justify right)
			)
		)
		(property "Value" "C_100n_0402"
			(at 71.12 149.86 0)
			(effects
				(font
					(size 1.27 1.27)
					(thickness 0.15)
				)
				(justify left bottom)
				(hide yes)
			)
		)
		(property "Footprint" "antmicro-footprints:C_0402_1005Metric"
			(at 73.66 149.86 0)
			(effects
				(font
					(size 1.27 1.27)
					(thickness 0.15)
				)
				(justify left bottom)
				(hide yes)
			)
		)
		(property "Datasheet" "https://www.murata.com/products/productdetail?partno=GRM155R61H104KE14%23"
			(at 76.2 149.86 0)
			(effects
				(font
					(size 1.27 1.27)
					(thickness 0.15)
				)
				(justify left bottom)
				(hide yes)
			)
		)
		(property "Description" "SMD Multilayer Ceramic Capacitor, 0.1 µF, 50 V, 0402 [1005 Metric], ± 10%, X5R, GRM Series"
			(at 93.98 149.86 0)
			(effects
				(font
					(size 1.27 1.27)
				)
				(justify left bottom)
				(hide yes)
			)
		)
		(property "MPN" "GRM155R61H104KE14D"
			(at 78.74 149.86 0)
			(effects
				(font
					(size 1.27 1.27)
					(thickness 0.15)
				)
				(justify left bottom)
				(hide yes)
			)
		)
		(property "Manufacturer" "Murata"
			(at 81.28 149.86 0)
			(effects
				(font
					(size 1.27 1.27)
					(thickness 0.15)
				)
				(justify left bottom)
				(hide yes)
			)
		)
		(property "License" "Apache-2.0"
			(at 83.82 149.86 0)
			(effects
				(font
					(size 1.27 1.27)
					(thickness 0.15)
				)
				(justify left bottom)
				(hide yes)
			)
		)
		(property "Author" "Antmicro"
			(at 86.36 149.86 0)
			(effects
				(font
					(size 1.27 1.27)
					(thickness 0.15)
				)
				(justify left bottom)
				(hide yes)
			)
		)
		(property "Val" "100n"
			(at 63.5 168.9036 90)
			(effects
				(font
					(size 1.27 1.27)
					(thickness 0.15)
				)
				(justify right)
			)
		)
		(property "Voltage" "50V"
			(at 88.9 149.86 0)
			(effects
				(font
					(size 1.27 1.27)
				)
				(justify left bottom)
				(hide yes)
			)
		)
		(property "Dielectric" "X5R"
			(at 91.44 149.86 0)
			(effects
				(font
					(size 1.27 1.27)
				)
				(justify left bottom)
				(hide yes)
			)
		)
		(pin "2"
		)
		(pin "1"
		)
		(instances
			(project ""
				(path ""
					(reference "C40")
					(unit 1)
				)
			)
		)
	)
	(symbol
		(lib_id "antmicroTVSDiodes:TPD4E05U06QDQARQ1")
		(at 217.17 153.67 270)
		(unit 1)
		(exclude_from_sim no)
		(in_bom no)
		(on_board yes)
		(dnp yes)
		(property "Reference" "U4"
			(at 205.232 163.83 90)
			(effects
				(font
					(size 1.27 1.27)
				)
				(justify left)
			)
		)
		(property "Value" "TPD4E05U06QDQARQ1"
			(at 207.01 177.8 0)
			(effects
				(font
					(size 1.27 1.27)
					(thickness 0.15)
				)
				(justify left bottom)
				(hide yes)
			)
		)
		(property "Footprint" "antmicro-footprints:USON-10_2.5x1mm_P0.5mm"
			(at 212.09 177.8 0)
			(effects
				(font
					(size 1.27 1.27)
					(thickness 0.15)
				)
				(justify left bottom)
				(hide yes)
			)
		)
		(property "Datasheet" "https://www.ti.com/lit/ds/symlink/tpd4e05u06-q1.pdf?HQS=dis-mous-null-mousermode-dsf-pf-null-wwe&ts=1663591265741&ref_url=https%253A%252F%252Fwww.mouser.com%252F"
			(at 209.55 177.8 0)
			(effects
				(font
					(size 1.27 1.27)
					(thickness 0.15)
				)
				(justify left bottom)
				(hide yes)
			)
		)
		(property "Description" "TVS diode array, 12 kV, USON-10, 5.5 V, 0.5 pF"
			(at 217.17 153.67 0)
			(effects
				(font
					(size 1.27 1.27)
				)
				(hide yes)
			)
		)
		(property "Manufacturer" "Texas Instruments"
			(at 204.47 177.8 0)
			(effects
				(font
					(size 1.27 1.27)
					(thickness 0.15)
				)
				(justify left bottom)
				(hide yes)
			)
		)
		(property "MPN" "TPD4E05U06QDQARQ1"
			(at 205.232 166.116 90)
			(effects
				(font
					(size 1.27 1.27)
					(thickness 0.15)
				)
				(justify left)
			)
		)
		(property "Author" "Antmicro"
			(at 201.93 177.8 0)
			(effects
				(font
					(size 1.27 1.27)
					(thickness 0.15)
				)
				(justify left bottom)
				(hide yes)
			)
		)
		(property "License" "Apache-2.0"
			(at 199.39 177.8 0)
			(effects
				(font
					(size 1.27 1.27)
					(thickness 0.15)
				)
				(justify left bottom)
				(hide yes)
			)
		)
		(pin "1"
		)
		(pin "10"
		)
		(pin "2"
		)
		(pin "3"
		)
		(pin "4"
		)
		(pin "5"
		)
		(pin "6"
		)
		(pin "7"
		)
		(pin "8"
		)
		(pin "9"
		)
		(instances
			(project "jetson-agx-thor-baseboard"
				(path ""
					(reference "U4")
					(unit 1)
				)
			)
		)
	)
	(symbol
		(lib_id "antmicroCapacitors0402:C_100n_0402")
		(at 163.83 63.5 90)
		(unit 1)
		(exclude_from_sim no)
		(in_bom yes)
		(on_board yes)
		(dnp no)
		(property "Reference" "C272"
			(at 158.242 59.182 90)
			(effects
				(font
					(size 1.27 1.27)
					(thickness 0.15)
				)
				(justify right)
			)
		)
		(property "Value" "C_100n_0402"
			(at 186.69 48.26 0)
			(effects
				(font
					(size 1.27 1.27)
					(thickness 0.15)
				)
				(justify left bottom)
				(hide yes)
			)
		)
		(property "Footprint" "antmicro-footprints:C_0402_1005Metric"
			(at 189.23 48.26 0)
			(effects
				(font
					(size 1.27 1.27)
					(thickness 0.15)
				)
				(justify left bottom)
				(hide yes)
			)
		)
		(property "Datasheet" "https://www.murata.com/products/productdetail?partno=GRM155R61H104KE14%23"
			(at 191.77 48.26 0)
			(effects
				(font
					(size 1.27 1.27)
					(thickness 0.15)
				)
				(justify left bottom)
				(hide yes)
			)
		)
		(property "Description" "SMD Multilayer Ceramic Capacitor, 0.1 µF, 50 V, 0402 [1005 Metric], ± 10%, X5R, GRM Series"
			(at 163.83 63.5 0)
			(effects
				(font
					(size 1.27 1.27)
				)
				(hide yes)
			)
		)
		(property "MPN" "GRM155R61H104KE14D"
			(at 194.31 48.26 0)
			(effects
				(font
					(size 1.27 1.27)
					(thickness 0.15)
				)
				(justify left bottom)
				(hide yes)
			)
		)
		(property "Val" "100n"
			(at 158.242 62.484 90)
			(effects
				(font
					(size 1.27 1.27)
					(thickness 0.15)
				)
				(justify right)
			)
		)
		(property "Voltage" "50V"
			(at 173.99 48.26 0)
			(effects
				(font
					(size 1.27 1.27)
					(thickness 0.15)
				)
				(justify left bottom)
				(hide yes)
			)
		)
		(property "Dielectric" "X5R"
			(at 176.53 48.26 0)
			(effects
				(font
					(size 1.27 1.27)
					(thickness 0.15)
				)
				(justify left bottom)
				(hide yes)
			)
		)
		(property "Manufacturer" "Murata"
			(at 179.07 48.26 0)
			(effects
				(font
					(size 1.27 1.27)
					(thickness 0.15)
				)
				(justify left bottom)
				(hide yes)
			)
		)
		(property "License" "Apache-2.0"
			(at 181.61 48.26 0)
			(effects
				(font
					(size 1.27 1.27)
					(thickness 0.15)
				)
				(justify left bottom)
				(hide yes)
			)
		)
		(property "Author" "Antmicro"
			(at 184.15 48.26 0)
			(effects
				(font
					(size 1.27 1.27)
					(thickness 0.15)
				)
				(justify left bottom)
				(hide yes)
			)
		)
		(pin "1"
		)
		(pin "2"
		)
		(instances
			(project "jetson-agx-thor-baseboard"
				(path ""
					(reference "C272")
					(unit 1)
				)
			)
		)
	)
	(symbol
		(lib_id "antmicropower:GND")
		(at 95.25 241.3 0)
		(unit 1)
		(exclude_from_sim no)
		(in_bom yes)
		(on_board yes)
		(dnp no)
		(property "Reference" "#PWR0577"
			(at 104.14 243.84 0)
			(effects
				(font
					(size 1.27 1.27)
					(thickness 0.15)
				)
				(justify left bottom)
				(hide yes)
			)
		)
		(property "Value" "GND"
			(at 95.25 245.11 0)
			(effects
				(font
					(size 1.27 1.27)
					(thickness 0.15)
				)
			)
		)
		(property "Footprint" ""
			(at 104.14 248.92 0)
			(effects
				(font
					(size 1.27 1.27)
					(thickness 0.15)
				)
				(justify left bottom)
				(hide yes)
			)
		)
		(property "Datasheet" ""
			(at 104.14 254 0)
			(effects
				(font
					(size 1.27 1.27)
					(thickness 0.15)
				)
				(justify left bottom)
				(hide yes)
			)
		)
		(property "Description" ""
			(at 95.25 241.3 0)
			(effects
				(font
					(size 1.27 1.27)
				)
				(hide yes)
			)
		)
		(property "Author" "Antmicro"
			(at 104.14 248.92 0)
			(effects
				(font
					(size 1.27 1.27)
					(thickness 0.15)
				)
				(justify left bottom)
				(hide yes)
			)
		)
		(property "License" "Apache-2.0"
			(at 104.14 251.46 0)
			(effects
				(font
					(size 1.27 1.27)
					(thickness 0.15)
				)
				(justify left bottom)
				(hide yes)
			)
		)
		(pin "1"
		)
		(instances
			(project "jetson-agx-thor-baseboard"
				(path ""
					(reference "#PWR0577")
					(unit 1)
				)
			)
		)
	)
	(symbol
		(lib_id "antmicroCapacitors0402:C_10u_0402")
		(at 124.46 48.26 90)
		(unit 1)
		(exclude_from_sim no)
		(in_bom yes)
		(on_board yes)
		(dnp no)
		(fields_autoplaced yes)
		(property "Reference" "C15"
			(at 127 44.4436 90)
			(effects
				(font
					(size 1.27 1.27)
					(thickness 0.15)
				)
				(justify right)
			)
		)
		(property "Value" "C_10u_0402"
			(at 134.62 27.94 0)
			(effects
				(font
					(size 1.27 1.27)
					(thickness 0.15)
				)
				(justify left bottom)
				(hide yes)
			)
		)
		(property "Footprint" "antmicro-footprints:C_0402_1005Metric"
			(at 137.16 27.94 0)
			(effects
				(font
					(size 1.27 1.27)
					(thickness 0.15)
				)
				(justify left bottom)
				(hide yes)
			)
		)
		(property "Datasheet" "https://www.yageo.com/en/Chart/Download/pdf/CC0402MRX5R5BB106"
			(at 139.7 27.94 0)
			(effects
				(font
					(size 1.27 1.27)
					(thickness 0.15)
				)
				(justify left bottom)
				(hide yes)
			)
		)
		(property "Description" "SMD Multilayer Ceramic Capacitor, 10 µF, 6.3 V, 0402 [1005 Metric], ± 20%, X5R, CC Series"
			(at 124.46 48.26 0)
			(effects
				(font
					(size 1.27 1.27)
				)
				(hide yes)
			)
		)
		(property "MPN" "CC0402MRX5R5BB106"
			(at 142.24 27.94 0)
			(effects
				(font
					(size 1.27 1.27)
					(thickness 0.15)
				)
				(justify left bottom)
				(hide yes)
			)
		)
		(property "Manufacturer" "YAGEO"
			(at 144.78 27.94 0)
			(effects
				(font
					(size 1.27 1.27)
					(thickness 0.15)
				)
				(justify left bottom)
				(hide yes)
			)
		)
		(property "License" "Apache-2.0"
			(at 147.32 27.94 0)
			(effects
				(font
					(size 1.27 1.27)
					(thickness 0.15)
				)
				(justify left bottom)
				(hide yes)
			)
		)
		(property "Author" "Antmicro"
			(at 149.86 27.94 0)
			(effects
				(font
					(size 1.27 1.27)
					(thickness 0.15)
				)
				(justify left bottom)
				(hide yes)
			)
		)
		(property "Val" "10u"
			(at 127 46.9836 90)
			(effects
				(font
					(size 1.27 1.27)
					(thickness 0.15)
				)
				(justify right)
			)
		)
		(property "Voltage" ""
			(at 152.4 27.94 0)
			(effects
				(font
					(size 1.27 1.27)
				)
				(justify left bottom)
				(hide yes)
			)
		)
		(property "Dielectric" "template_dielectric"
			(at 154.94 27.94 0)
			(effects
				(font
					(size 1.27 1.27)
				)
				(justify left bottom)
				(hide yes)
			)
		)
		(pin "1"
		)
		(pin "2"
		)
		(instances
			(project "jetson-agx-thor-baseboard"
				(path ""
					(reference "C15")
					(unit 1)
				)
			)
		)
	)
	(symbol
		(lib_id "antmicropower:+3V3_AON")
		(at 391.16 201.93 0)
		(unit 1)
		(exclude_from_sim no)
		(in_bom yes)
		(on_board yes)
		(dnp no)
		(property "Reference" "#PWR0667"
			(at 391.16 205.74 0)
			(effects
				(font
					(size 1.27 1.27)
				)
				(hide yes)
			)
		)
		(property "Value" "+1V8"
			(at 390.652 197.866 0)
			(effects
				(font
					(size 1.27 1.27)
				)
			)
		)
		(property "Footprint" ""
			(at 391.16 201.93 0)
			(effects
				(font
					(size 1.27 1.27)
				)
				(hide yes)
			)
		)
		(property "Datasheet" ""
			(at 391.16 201.93 0)
			(effects
				(font
					(size 1.27 1.27)
				)
				(hide yes)
			)
		)
		(property "Description" ""
			(at 391.16 201.93 0)
			(effects
				(font
					(size 1.27 1.27)
				)
				(hide yes)
			)
		)
		(pin "1"
		)
		(instances
			(project "jetson-agx-thor-baseboard"
				(path ""
					(reference "#PWR0667")
					(unit 1)
				)
			)
		)
	)
	(symbol
		(lib_id "antmicropower:GND")
		(at 97.79 40.64 0)
		(unit 1)
		(exclude_from_sim no)
		(in_bom yes)
		(on_board yes)
		(dnp no)
		(fields_autoplaced yes)
		(property "Reference" "#PWR035"
			(at 106.68 43.18 0)
			(effects
				(font
					(size 1.27 1.27)
					(thickness 0.15)
				)
				(justify left bottom)
				(hide yes)
			)
		)
		(property "Value" "GND"
			(at 97.79 45.72 0)
			(effects
				(font
					(size 1.27 1.27)
					(thickness 0.15)
				)
			)
		)
		(property "Footprint" ""
			(at 106.68 48.26 0)
			(effects
				(font
					(size 1.27 1.27)
					(thickness 0.15)
				)
				(justify left bottom)
				(hide yes)
			)
		)
		(property "Datasheet" ""
			(at 106.68 53.34 0)
			(effects
				(font
					(size 1.27 1.27)
					(thickness 0.15)
				)
				(justify left bottom)
				(hide yes)
			)
		)
		(property "Description" ""
			(at 97.79 40.64 0)
			(effects
				(font
					(size 1.27 1.27)
				)
				(hide yes)
			)
		)
		(property "Author" "Antmicro"
			(at 106.68 48.26 0)
			(effects
				(font
					(size 1.27 1.27)
					(thickness 0.15)
				)
				(justify left bottom)
				(hide yes)
			)
		)
		(property "License" "Apache-2.0"
			(at 106.68 50.8 0)
			(effects
				(font
					(size 1.27 1.27)
					(thickness 0.15)
				)
				(justify left bottom)
				(hide yes)
			)
		)
		(pin "1"
		)
		(instances
			(project "jetson-agx-thor-baseboard"
				(path ""
					(reference "#PWR035")
					(unit 1)
				)
			)
		)
	)
	(symbol
		(lib_id "antmicroMechanicalParts:Spacer_Drill4.45mm_H4mm_9774040960R")
		(at 378.46 59.69 0)
		(unit 1)
		(exclude_from_sim no)
		(in_bom yes)
		(on_board yes)
		(dnp no)
		(property "Reference" "H8"
			(at 387.35 58.42 0)
			(effects
				(font
					(size 1.27 1.27)
					(thickness 0.15)
				)
				(justify left)
			)
		)
		(property "Value" "Spacer_Drill4.45mm_H4mm_9774040960R"
			(at 387.35 60.96 0)
			(effects
				(font
					(size 1.27 1.27)
					(thickness 0.15)
				)
				(justify left)
				(hide yes)
			)
		)
		(property "Footprint" "antmicro-footprints:Spacer_Drill4.45mm_H4mm_9774040960R"
			(at 401.32 67.31 0)
			(effects
				(font
					(size 1.27 1.27)
					(thickness 0.15)
				)
				(justify left bottom)
				(hide yes)
			)
		)
		(property "Datasheet" "https://www.we-online.com/components/products/datasheet/9774040960R.pdf"
			(at 401.32 69.85 0)
			(effects
				(font
					(size 1.27 1.27)
					(thickness 0.15)
				)
				(justify left bottom)
				(hide yes)
			)
		)
		(property "Description" "Spacer, SMT, Non Stop, Steel, Swage Round, 6 mm x 4 mm, 3.3 mm Internal, WA-SMST Series"
			(at 378.46 59.69 0)
			(effects
				(font
					(size 1.27 1.27)
				)
				(hide yes)
			)
		)
		(property "Manufacturer" "Würth Elektronik"
			(at 401.32 72.39 0)
			(effects
				(font
					(size 1.27 1.27)
					(thickness 0.15)
				)
				(justify left bottom)
				(hide yes)
			)
		)
		(property "MPN" "9774040960R"
			(at 387.35 61.722 0)
			(effects
				(font
					(size 1.27 1.27)
					(thickness 0.15)
				)
				(justify left bottom)
			)
		)
		(property "Author" "Antmicro"
			(at 401.32 77.47 0)
			(effects
				(font
					(size 1.27 1.27)
					(thickness 0.15)
				)
				(justify left bottom)
				(hide yes)
			)
		)
		(property "License" "Apache-2.0"
			(at 401.32 80.01 0)
			(effects
				(font
					(size 1.27 1.27)
					(thickness 0.15)
				)
				(justify left bottom)
				(hide yes)
			)
		)
		(pin "1"
		)
		(instances
			(project "jetson-agx-thor-baseboard"
				(path ""
					(reference "H8")
					(unit 1)
				)
			)
		)
	)
	(symbol
		(lib_id "antmicroResistors0402:R_499k_0402")
		(at 38.1 152.4 90)
		(unit 1)
		(exclude_from_sim no)
		(in_bom yes)
		(on_board yes)
		(dnp no)
		(fields_autoplaced yes)
		(property "Reference" "R19"
			(at 40.64 148.59 90)
			(effects
				(font
					(size 1.27 1.27)
					(thickness 0.15)
				)
				(justify right)
			)
		)
		(property "Value" "R_499k_0402"
			(at 50.8 132.08 0)
			(effects
				(font
					(size 1.27 1.27)
					(thickness 0.15)
				)
				(justify left bottom)
				(hide yes)
			)
		)
		(property "Footprint" "antmicro-footprints:R_0402_1005Metric"
			(at 53.34 132.08 0)
			(effects
				(font
					(size 1.27 1.27)
					(thickness 0.15)
				)
				(justify left bottom)
				(hide yes)
			)
		)
		(property "Datasheet" "https://www.mouser.com/datasheet/2/54/cr-1858361.pdf"
			(at 55.88 132.08 0)
			(effects
				(font
					(size 1.27 1.27)
					(thickness 0.15)
				)
				(justify left bottom)
				(hide yes)
			)
		)
		(property "Description" "SMD Chip Resistor, 499 kohm, ± 1%, 63 mW, 0402 [1005 Metric], Thick Film, General Purpose"
			(at 38.1 152.4 0)
			(effects
				(font
					(size 1.27 1.27)
				)
				(hide yes)
			)
		)
		(property "MPN" "CR0402-FX-4993GLF"
			(at 58.42 132.08 0)
			(effects
				(font
					(size 1.27 1.27)
					(thickness 0.15)
				)
				(justify left bottom)
				(hide yes)
			)
		)
		(property "Manufacturer" "Bourns"
			(at 60.96 132.08 0)
			(effects
				(font
					(size 1.27 1.27)
					(thickness 0.15)
				)
				(justify left bottom)
				(hide yes)
			)
		)
		(property "License" "Apache-2.0"
			(at 63.5 132.08 0)
			(effects
				(font
					(size 1.27 1.27)
					(thickness 0.15)
				)
				(justify left bottom)
				(hide yes)
			)
		)
		(property "Author" "Antmicro"
			(at 66.04 132.08 0)
			(effects
				(font
					(size 1.27 1.27)
					(thickness 0.15)
				)
				(justify left bottom)
				(hide yes)
			)
		)
		(property "Val" "499k"
			(at 40.64 151.13 90)
			(effects
				(font
					(size 1.27 1.27)
					(thickness 0.15)
				)
				(justify right)
			)
		)
		(property "Tolerance" "1%"
			(at 48.26 132.08 0)
			(effects
				(font
					(size 1.27 1.27)
				)
				(justify left bottom)
				(hide yes)
			)
		)
		(pin "2"
		)
		(pin "1"
		)
		(instances
			(project "jetson-agx-thor-baseboard"
				(path ""
					(reference "R19")
					(unit 1)
				)
			)
		)
	)
	(symbol
		(lib_id "antmicroTestPoints:TP_0.75mm_SMD")
		(at 128.27 200.66 90)
		(unit 1)
		(exclude_from_sim no)
		(in_bom no)
		(on_board yes)
		(dnp no)
		(property "Reference" "TP117"
			(at 128.27 195.58 90)
			(effects
				(font
					(size 1.27 1.27)
					(thickness 0.15)
				)
			)
		)
		(property "Value" "TP_0.75mm_SMD"
			(at 132.08 190.5 0)
			(effects
				(font
					(size 1.27 1.27)
					(thickness 0.15)
				)
				(justify left bottom)
				(hide yes)
			)
		)
		(property "Footprint" "antmicro-footprints:TP_SMD_0.75mm"
			(at 134.62 190.5 0)
			(effects
				(font
					(size 1.27 1.27)
					(thickness 0.15)
				)
				(justify left bottom)
				(hide yes)
			)
		)
		(property "Datasheet" ""
			(at 140.97 182.88 0)
			(effects
				(font
					(size 1.27 1.27)
					(thickness 0.15)
				)
				(justify left bottom)
				(hide yes)
			)
		)
		(property "Description" "SMT test point"
			(at 128.27 200.66 0)
			(effects
				(font
					(size 1.27 1.27)
				)
				(hide yes)
			)
		)
		(property "MPN" ""
			(at 139.7 189.865 0)
			(effects
				(font
					(size 1.27 1.27)
					(thickness 0.15)
				)
				(justify left bottom)
				(hide yes)
			)
		)
		(property "Manufacturer" ""
			(at 134.62 189.865 0)
			(effects
				(font
					(size 1.27 1.27)
					(thickness 0.15)
				)
				(justify left bottom)
				(hide yes)
			)
		)
		(property "Author" "Antmicro"
			(at 137.16 190.5 0)
			(effects
				(font
					(size 1.27 1.27)
					(thickness 0.15)
				)
				(justify left bottom)
				(hide yes)
			)
		)
		(property "License" "Apache-2.0"
			(at 139.7 190.5 0)
			(effects
				(font
					(size 1.27 1.27)
					(thickness 0.15)
				)
				(justify left bottom)
				(hide yes)
			)
		)
		(pin "1"
		)
		(instances
			(project "jetson-agx-thor-baseboard"
				(path ""
					(reference "TP117")
					(unit 1)
				)
			)
		)
	)
	(symbol
		(lib_id "antmicroTransistorsFETsMOSFETsSingle:DMG1012T-7")
		(at 121.92 243.84 0)
		(unit 1)
		(exclude_from_sim no)
		(in_bom yes)
		(on_board yes)
		(dnp no)
		(fields_autoplaced yes)
		(property "Reference" "Q22"
			(at 132.08 240.03 0)
			(effects
				(font
					(size 1.27 1.27)
					(thickness 0.15)
				)
				(justify left)
			)
		)
		(property "Value" "DMG1012T-7"
			(at 144.78 248.92 0)
			(effects
				(font
					(size 1.27 1.27)
					(thickness 0.15)
				)
				(justify left bottom)
				(hide yes)
			)
		)
		(property "Footprint" "antmicro-footprints:SOT-523"
			(at 144.78 251.46 0)
			(effects
				(font
					(size 1.27 1.27)
					(thickness 0.15)
				)
				(justify left bottom)
				(hide yes)
			)
		)
		(property "Datasheet" "https://www.diodes.com/assets/Datasheets/ds31783.pdf"
			(at 144.78 254 0)
			(effects
				(font
					(size 1.27 1.27)
					(thickness 0.15)
				)
				(justify left bottom)
				(hide yes)
			)
		)
		(property "Description" "Power MOSFET, N Channel, 20 V, 630 mA, 0.3 ohm, SOT-523, Surface Mount"
			(at 181.864 265.684 0)
			(effects
				(font
					(size 1.27 1.27)
				)
				(hide yes)
			)
		)
		(property "MPN" "DMG1012T-7"
			(at 132.08 242.57 0)
			(effects
				(font
					(size 1.27 1.27)
					(thickness 0.15)
				)
				(justify left)
			)
		)
		(property "Manufacturer" "Diodes Incorporated"
			(at 144.78 259.08 0)
			(effects
				(font
					(size 1.27 1.27)
					(thickness 0.15)
				)
				(justify left bottom)
				(hide yes)
			)
		)
		(property "Author" "Antmicro"
			(at 144.78 261.62 0)
			(effects
				(font
					(size 1.27 1.27)
					(thickness 0.15)
				)
				(justify left bottom)
				(hide yes)
			)
		)
		(property "License" "Apache-2.0"
			(at 144.78 264.16 0)
			(effects
				(font
					(size 1.27 1.27)
					(thickness 0.15)
				)
				(justify left bottom)
				(hide yes)
			)
		)
		(pin "2"
		)
		(pin "3"
		)
		(pin "1"
		)
		(instances
			(project ""
				(path ""
					(reference "Q22")
					(unit 1)
				)
			)
		)
	)
	(symbol
		(lib_id "antmicroTransistorsFETsMOSFETsSingle:DMG1012T-7")
		(at 209.55 274.32 0)
		(unit 1)
		(exclude_from_sim no)
		(in_bom yes)
		(on_board yes)
		(dnp no)
		(fields_autoplaced yes)
		(property "Reference" "Q18"
			(at 219.71 270.51 0)
			(effects
				(font
					(size 1.27 1.27)
					(thickness 0.15)
				)
				(justify left)
			)
		)
		(property "Value" "DMG1012T-7"
			(at 232.41 283.21 0)
			(effects
				(font
					(size 1.27 1.27)
					(thickness 0.15)
				)
				(justify left bottom)
				(hide yes)
			)
		)
		(property "Footprint" "antmicro-footprints:SOT-523"
			(at 232.41 285.75 0)
			(effects
				(font
					(size 1.27 1.27)
					(thickness 0.15)
				)
				(justify left bottom)
				(hide yes)
			)
		)
		(property "Datasheet" "https://www.diodes.com/assets/Datasheets/ds31783.pdf"
			(at 232.41 288.29 0)
			(effects
				(font
					(size 1.27 1.27)
					(thickness 0.15)
				)
				(justify left bottom)
				(hide yes)
			)
		)
		(property "Description" "Power MOSFET, N Channel, 20 V, 630 mA, 0.3 ohm, SOT-523, Surface Mount"
			(at 232.41 300.99 0)
			(effects
				(font
					(size 1.27 1.27)
				)
				(justify left bottom)
				(hide yes)
			)
		)
		(property "MPN" "DMG1012T-7"
			(at 219.71 273.05 0)
			(effects
				(font
					(size 1.27 1.27)
					(thickness 0.15)
				)
				(justify left)
			)
		)
		(property "Manufacturer" "Diodes Incorporated"
			(at 232.41 293.37 0)
			(effects
				(font
					(size 1.27 1.27)
					(thickness 0.15)
				)
				(justify left bottom)
				(hide yes)
			)
		)
		(property "Author" "Antmicro"
			(at 232.41 295.91 0)
			(effects
				(font
					(size 1.27 1.27)
					(thickness 0.15)
				)
				(justify left bottom)
				(hide yes)
			)
		)
		(property "License" "Apache-2.0"
			(at 232.41 298.45 0)
			(effects
				(font
					(size 1.27 1.27)
					(thickness 0.15)
				)
				(justify left bottom)
				(hide yes)
			)
		)
		(pin "3"
		)
		(pin "1"
		)
		(pin "2"
		)
		(instances
			(project "jetson-agx-thor-baseboard"
				(path ""
					(reference "Q18")
					(unit 1)
				)
			)
		)
	)
	(symbol
		(lib_id "antmicropower:GND")
		(at 161.29 248.92 0)
		(unit 1)
		(exclude_from_sim no)
		(in_bom yes)
		(on_board yes)
		(dnp no)
		(property "Reference" "#PWR0432"
			(at 170.18 251.46 0)
			(effects
				(font
					(size 1.27 1.27)
					(thickness 0.15)
				)
				(justify left bottom)
				(hide yes)
			)
		)
		(property "Value" "GND"
			(at 161.29 252.73 0)
			(effects
				(font
					(size 1.27 1.27)
					(thickness 0.15)
				)
			)
		)
		(property "Footprint" ""
			(at 170.18 256.54 0)
			(effects
				(font
					(size 1.27 1.27)
					(thickness 0.15)
				)
				(justify left bottom)
				(hide yes)
			)
		)
		(property "Datasheet" ""
			(at 170.18 261.62 0)
			(effects
				(font
					(size 1.27 1.27)
					(thickness 0.15)
				)
				(justify left bottom)
				(hide yes)
			)
		)
		(property "Description" ""
			(at 170.18 264.16 0)
			(effects
				(font
					(size 1.27 1.27)
				)
				(justify left bottom)
				(hide yes)
			)
		)
		(property "Author" "Antmicro"
			(at 170.18 256.54 0)
			(effects
				(font
					(size 1.27 1.27)
					(thickness 0.15)
				)
				(justify left bottom)
				(hide yes)
			)
		)
		(property "License" "Apache-2.0"
			(at 170.18 259.08 0)
			(effects
				(font
					(size 1.27 1.27)
					(thickness 0.15)
				)
				(justify left bottom)
				(hide yes)
			)
		)
		(pin "1"
		)
		(instances
			(project "jetson-agx-thor-baseboard"
				(path ""
					(reference "#PWR0432")
					(unit 1)
				)
			)
		)
	)
	(symbol
		(lib_id "antmicroTestPoints:TP_0.75mm_SMD")
		(at 196.85 273.05 90)
		(unit 1)
		(exclude_from_sim no)
		(in_bom no)
		(on_board yes)
		(dnp no)
		(property "Reference" "TP84"
			(at 195.072 267.716 90)
			(effects
				(font
					(size 1.27 1.27)
					(thickness 0.15)
				)
				(justify right)
			)
		)
		(property "Value" "TP_0.75mm_SMD"
			(at 200.66 262.89 0)
			(effects
				(font
					(size 1.27 1.27)
					(thickness 0.15)
				)
				(justify left bottom)
				(hide yes)
			)
		)
		(property "Footprint" "antmicro-footprints:TP_SMD_0.75mm"
			(at 203.2 262.89 0)
			(effects
				(font
					(size 1.27 1.27)
					(thickness 0.15)
				)
				(justify left bottom)
				(hide yes)
			)
		)
		(property "Datasheet" ""
			(at 209.55 255.27 0)
			(effects
				(font
					(size 1.27 1.27)
					(thickness 0.15)
				)
				(justify left bottom)
				(hide yes)
			)
		)
		(property "Description" "SMT test point"
			(at 196.85 273.05 0)
			(effects
				(font
					(size 1.27 1.27)
				)
				(hide yes)
			)
		)
		(property "MPN" ""
			(at 208.28 262.255 0)
			(effects
				(font
					(size 1.27 1.27)
					(thickness 0.15)
				)
				(justify left bottom)
				(hide yes)
			)
		)
		(property "Manufacturer" ""
			(at 203.2 262.255 0)
			(effects
				(font
					(size 1.27 1.27)
					(thickness 0.15)
				)
				(justify left bottom)
				(hide yes)
			)
		)
		(property "Author" "Antmicro"
			(at 205.74 262.89 0)
			(effects
				(font
					(size 1.27 1.27)
					(thickness 0.15)
				)
				(justify left bottom)
				(hide yes)
			)
		)
		(property "License" "Apache-2.0"
			(at 208.28 262.89 0)
			(effects
				(font
					(size 1.27 1.27)
					(thickness 0.15)
				)
				(justify left bottom)
				(hide yes)
			)
		)
		(pin "1"
		)
		(instances
			(project "jetson-agx-thor-baseboard"
				(path ""
					(reference "TP84")
					(unit 1)
				)
			)
		)
	)
	(symbol
		(lib_id "antmicroTransistorsFETsMOSFETsSingle:DMG1012T-7")
		(at 213.36 210.82 270)
		(unit 1)
		(exclude_from_sim no)
		(in_bom yes)
		(on_board yes)
		(dnp no)
		(fields_autoplaced yes)
		(property "Reference" "Q17"
			(at 215.9 220.98 90)
			(effects
				(font
					(size 1.27 1.27)
					(thickness 0.15)
				)
			)
		)
		(property "Value" "DMG1012T-7"
			(at 204.47 233.68 0)
			(effects
				(font
					(size 1.27 1.27)
					(thickness 0.15)
				)
				(justify left bottom)
				(hide yes)
			)
		)
		(property "Footprint" "antmicro-footprints:SOT-523"
			(at 201.93 233.68 0)
			(effects
				(font
					(size 1.27 1.27)
					(thickness 0.15)
				)
				(justify left bottom)
				(hide yes)
			)
		)
		(property "Datasheet" "https://www.diodes.com/assets/Datasheets/ds31783.pdf"
			(at 199.39 233.68 0)
			(effects
				(font
					(size 1.27 1.27)
					(thickness 0.15)
				)
				(justify left bottom)
				(hide yes)
			)
		)
		(property "Description" "Power MOSFET, N Channel, 20 V, 630 mA, 0.3 ohm, SOT-523, Surface Mount"
			(at 186.69 233.68 0)
			(effects
				(font
					(size 1.27 1.27)
				)
				(justify left bottom)
				(hide yes)
			)
		)
		(property "MPN" "DMG1012T-7"
			(at 215.9 223.52 90)
			(effects
				(font
					(size 1.27 1.27)
					(thickness 0.15)
				)
			)
		)
		(property "Manufacturer" "Diodes Incorporated"
			(at 194.31 233.68 0)
			(effects
				(font
					(size 1.27 1.27)
					(thickness 0.15)
				)
				(justify left bottom)
				(hide yes)
			)
		)
		(property "Author" "Antmicro"
			(at 191.77 233.68 0)
			(effects
				(font
					(size 1.27 1.27)
					(thickness 0.15)
				)
				(justify left bottom)
				(hide yes)
			)
		)
		(property "License" "Apache-2.0"
			(at 189.23 233.68 0)
			(effects
				(font
					(size 1.27 1.27)
					(thickness 0.15)
				)
				(justify left bottom)
				(hide yes)
			)
		)
		(pin "3"
		)
		(pin "1"
		)
		(pin "2"
		)
		(instances
			(project "jetson-agx-thor-baseboard"
				(path ""
					(reference "Q17")
					(unit 1)
				)
			)
		)
	)
	(symbol
		(lib_id "antmicropower:GND")
		(at 199.39 248.92 0)
		(unit 1)
		(exclude_from_sim no)
		(in_bom yes)
		(on_board yes)
		(dnp no)
		(property "Reference" "#PWR0177"
			(at 208.28 251.46 0)
			(effects
				(font
					(size 1.27 1.27)
					(thickness 0.15)
				)
				(justify left bottom)
				(hide yes)
			)
		)
		(property "Value" "GND"
			(at 199.39 252.73 0)
			(effects
				(font
					(size 1.27 1.27)
					(thickness 0.15)
				)
			)
		)
		(property "Footprint" ""
			(at 208.28 256.54 0)
			(effects
				(font
					(size 1.27 1.27)
					(thickness 0.15)
				)
				(justify left bottom)
				(hide yes)
			)
		)
		(property "Datasheet" ""
			(at 208.28 261.62 0)
			(effects
				(font
					(size 1.27 1.27)
					(thickness 0.15)
				)
				(justify left bottom)
				(hide yes)
			)
		)
		(property "Description" ""
			(at 208.28 264.16 0)
			(effects
				(font
					(size 1.27 1.27)
				)
				(justify left bottom)
				(hide yes)
			)
		)
		(property "Author" "Antmicro"
			(at 208.28 256.54 0)
			(effects
				(font
					(size 1.27 1.27)
					(thickness 0.15)
				)
				(justify left bottom)
				(hide yes)
			)
		)
		(property "License" "Apache-2.0"
			(at 208.28 259.08 0)
			(effects
				(font
					(size 1.27 1.27)
					(thickness 0.15)
				)
				(justify left bottom)
				(hide yes)
			)
		)
		(pin "1"
		)
		(instances
			(project ""
				(path ""
					(reference "#PWR0177")
					(unit 1)
				)
			)
		)
	)
	(symbol
		(lib_id "antmicropower:VCC")
		(at 82.55 30.48 0)
		(mirror y)
		(unit 1)
		(exclude_from_sim no)
		(in_bom yes)
		(on_board yes)
		(dnp no)
		(property "Reference" "#PWR0520"
			(at 82.55 34.29 0)
			(effects
				(font
					(size 1.27 1.27)
				)
				(hide yes)
			)
		)
		(property "Value" "+5V_SOM"
			(at 80.264 25.4 0)
			(effects
				(font
					(size 1.27 1.27)
				)
				(justify right)
			)
		)
		(property "Footprint" ""
			(at 82.55 30.48 0)
			(effects
				(font
					(size 1.27 1.27)
				)
				(hide yes)
			)
		)
		(property "Datasheet" ""
			(at 82.55 30.48 0)
			(effects
				(font
					(size 1.27 1.27)
				)
				(hide yes)
			)
		)
		(property "Description" ""
			(at 82.55 30.48 0)
			(effects
				(font
					(size 1.27 1.27)
				)
				(hide yes)
			)
		)
		(pin "1"
		)
		(instances
			(project "jetson-agx-thor-baseboard"
				(path ""
					(reference "#PWR0520")
					(unit 1)
				)
			)
		)
	)
	(symbol
		(lib_id "antmicroTestPoints:TP_0.75mm_SMD")
		(at 276.86 93.98 0)
		(unit 1)
		(exclude_from_sim no)
		(in_bom no)
		(on_board yes)
		(dnp no)
		(property "Reference" "TP82"
			(at 281.94 93.98 0)
			(effects
				(font
					(size 1.27 1.27)
					(thickness 0.15)
				)
				(justify left)
			)
		)
		(property "Value" "TP_0.75mm_SMD"
			(at 287.02 97.79 0)
			(effects
				(font
					(size 1.27 1.27)
					(thickness 0.15)
				)
				(justify left bottom)
				(hide yes)
			)
		)
		(property "Footprint" "antmicro-footprints:TP_SMD_0.75mm"
			(at 287.02 100.33 0)
			(effects
				(font
					(size 1.27 1.27)
					(thickness 0.15)
				)
				(justify left bottom)
				(hide yes)
			)
		)
		(property "Datasheet" ""
			(at 294.64 106.68 0)
			(effects
				(font
					(size 1.27 1.27)
					(thickness 0.15)
				)
				(justify left bottom)
				(hide yes)
			)
		)
		(property "Description" "SMT test point"
			(at 276.86 93.98 0)
			(effects
				(font
					(size 1.27 1.27)
				)
				(hide yes)
			)
		)
		(property "MPN" ""
			(at 287.655 105.41 0)
			(effects
				(font
					(size 1.27 1.27)
					(thickness 0.15)
				)
				(justify left bottom)
				(hide yes)
			)
		)
		(property "Manufacturer" ""
			(at 287.655 100.33 0)
			(effects
				(font
					(size 1.27 1.27)
					(thickness 0.15)
				)
				(justify left bottom)
				(hide yes)
			)
		)
		(property "Author" "Antmicro"
			(at 287.02 102.87 0)
			(effects
				(font
					(size 1.27 1.27)
					(thickness 0.15)
				)
				(justify left bottom)
				(hide yes)
			)
		)
		(property "License" "Apache-2.0"
			(at 287.02 105.41 0)
			(effects
				(font
					(size 1.27 1.27)
					(thickness 0.15)
				)
				(justify left bottom)
				(hide yes)
			)
		)
		(pin "1"
		)
		(instances
			(project "jetson-agx-thor-baseboard"
				(path ""
					(reference "TP82")
					(unit 1)
				)
			)
		)
	)
	(symbol
		(lib_id "antmicroTransistorsFETsMOSFETsSingle:DMG1012T-7")
		(at 213.36 234.95 270)
		(unit 1)
		(exclude_from_sim no)
		(in_bom yes)
		(on_board yes)
		(dnp no)
		(property "Reference" "Q30"
			(at 215.9 245.11 90)
			(effects
				(font
					(size 1.27 1.27)
					(thickness 0.15)
				)
			)
		)
		(property "Value" "DMG1012T-7"
			(at 209.55 245.11 0)
			(effects
				(font
					(size 1.27 1.27)
					(thickness 0.15)
				)
				(justify left bottom)
				(hide yes)
			)
		)
		(property "Footprint" "antmicro-footprints:SOT-523"
			(at 207.01 245.11 0)
			(effects
				(font
					(size 1.27 1.27)
					(thickness 0.15)
				)
				(justify left bottom)
				(hide yes)
			)
		)
		(property "Datasheet" "https://www.diodes.com/assets/Datasheets/ds31783.pdf"
			(at 204.47 245.11 0)
			(effects
				(font
					(size 1.27 1.27)
					(thickness 0.15)
				)
				(justify left bottom)
				(hide yes)
			)
		)
		(property "Description" "Power MOSFET, N Channel, 20 V, 630 mA, 0.3 ohm, SOT-523, Surface Mount"
			(at 196.85 245.11 0)
			(effects
				(font
					(size 1.27 1.27)
				)
				(justify left bottom)
				(hide yes)
			)
		)
		(property "MPN" "DMG1012T-7"
			(at 215.9 247.65 90)
			(effects
				(font
					(size 1.27 1.27)
					(thickness 0.15)
				)
			)
		)
		(property "Manufacturer" "Diodes Incorporated"
			(at 212.09 245.11 0)
			(effects
				(font
					(size 1.27 1.27)
					(thickness 0.15)
				)
				(justify left bottom)
				(hide yes)
			)
		)
		(property "Author" "Antmicro"
			(at 201.93 245.11 0)
			(effects
				(font
					(size 1.27 1.27)
					(thickness 0.15)
				)
				(justify left bottom)
				(hide yes)
			)
		)
		(property "License" "Apache-2.0"
			(at 199.39 245.11 0)
			(effects
				(font
					(size 1.27 1.27)
					(thickness 0.15)
				)
				(justify left bottom)
				(hide yes)
			)
		)
		(pin "3"
		)
		(pin "1"
		)
		(pin "2"
		)
		(instances
			(project ""
				(path ""
					(reference "Q30")
					(unit 1)
				)
			)
		)
	)
	(symbol
		(lib_id "antmicroResistors0402:R_470R_0402")
		(at 360.68 208.28 90)
		(unit 1)
		(exclude_from_sim no)
		(in_bom yes)
		(on_board yes)
		(dnp no)
		(property "Reference" "R56"
			(at 361.696 204.47 90)
			(effects
				(font
					(size 1.27 1.27)
					(thickness 0.15)
				)
				(justify right)
			)
		)
		(property "Value" "R_470R_0402"
			(at 373.38 187.96 0)
			(effects
				(font
					(size 1.27 1.27)
					(thickness 0.15)
				)
				(justify left bottom)
				(hide yes)
			)
		)
		(property "Footprint" "antmicro-footprints:R_0402_1005Metric"
			(at 375.92 187.96 0)
			(effects
				(font
					(size 1.27 1.27)
					(thickness 0.15)
				)
				(justify left bottom)
				(hide yes)
			)
		)
		(property "Datasheet" "https://www.bourns.com/docs/product-datasheets/cr.pdf"
			(at 378.46 187.96 0)
			(effects
				(font
					(size 1.27 1.27)
					(thickness 0.15)
				)
				(justify left bottom)
				(hide yes)
			)
		)
		(property "Description" "SMD Chip Resistor, 470 ohm, ± 1%, 62.5 mW, 0402 [1005 Metric], Thick Film, General Purpose"
			(at 360.68 208.28 0)
			(effects
				(font
					(size 1.27 1.27)
				)
				(hide yes)
			)
		)
		(property "MPN" "CR0402-FX-4700GLF"
			(at 381 187.96 0)
			(effects
				(font
					(size 1.27 1.27)
					(thickness 0.15)
				)
				(justify left bottom)
				(hide yes)
			)
		)
		(property "Manufacturer" "Bourns"
			(at 383.54 187.96 0)
			(effects
				(font
					(size 1.27 1.27)
					(thickness 0.15)
				)
				(justify left bottom)
				(hide yes)
			)
		)
		(property "License" "Apache-2.0"
			(at 386.08 187.96 0)
			(effects
				(font
					(size 1.27 1.27)
					(thickness 0.15)
				)
				(justify left bottom)
				(hide yes)
			)
		)
		(property "Author" "Antmicro"
			(at 388.62 187.96 0)
			(effects
				(font
					(size 1.27 1.27)
					(thickness 0.15)
				)
				(justify left bottom)
				(hide yes)
			)
		)
		(property "Val" "470R"
			(at 361.696 207.01 90)
			(effects
				(font
					(size 1.27 1.27)
					(thickness 0.15)
				)
				(justify right)
			)
		)
		(property "Tolerance" "1%"
			(at 370.84 187.96 0)
			(effects
				(font
					(size 1.27 1.27)
				)
				(justify left bottom)
				(hide yes)
			)
		)
		(pin "1"
		)
		(pin "2"
		)
		(instances
			(project "jetson-agx-thor-baseboard"
				(path ""
					(reference "R56")
					(unit 1)
				)
			)
		)
	)
	(symbol
		(lib_id "antmicropower:VCC")
		(at 38.1 144.78 0)
		(mirror y)
		(unit 1)
		(exclude_from_sim no)
		(in_bom yes)
		(on_board yes)
		(dnp no)
		(property "Reference" "#PWR071"
			(at 38.1 148.59 0)
			(effects
				(font
					(size 1.27 1.27)
				)
				(hide yes)
			)
		)
		(property "Value" "+5V_SOM"
			(at 35.814 139.7 0)
			(effects
				(font
					(size 1.27 1.27)
				)
				(justify right)
			)
		)
		(property "Footprint" ""
			(at 38.1 144.78 0)
			(effects
				(font
					(size 1.27 1.27)
				)
				(hide yes)
			)
		)
		(property "Datasheet" ""
			(at 38.1 144.78 0)
			(effects
				(font
					(size 1.27 1.27)
				)
				(hide yes)
			)
		)
		(property "Description" ""
			(at 38.1 144.78 0)
			(effects
				(font
					(size 1.27 1.27)
				)
				(hide yes)
			)
		)
		(pin "1"
		)
		(instances
			(project "jetson-agx-thor-baseboard"
				(path ""
					(reference "#PWR071")
					(unit 1)
				)
			)
		)
	)
	(symbol
		(lib_id "antmicroTestPoints:TP_0.75mm_SMD")
		(at 219.71 193.04 0)
		(unit 1)
		(exclude_from_sim no)
		(in_bom no)
		(on_board yes)
		(dnp no)
		(fields_autoplaced yes)
		(property "Reference" "TP121"
			(at 224.79 193.04 0)
			(effects
				(font
					(size 1.27 1.27)
					(thickness 0.15)
				)
				(justify left)
			)
		)
		(property "Value" "TP_0.75mm_SMD"
			(at 229.87 196.85 0)
			(effects
				(font
					(size 1.27 1.27)
					(thickness 0.15)
				)
				(justify left bottom)
				(hide yes)
			)
		)
		(property "Footprint" "antmicro-footprints:TP_SMD_0.75mm"
			(at 229.87 199.39 0)
			(effects
				(font
					(size 1.27 1.27)
					(thickness 0.15)
				)
				(justify left bottom)
				(hide yes)
			)
		)
		(property "Datasheet" ""
			(at 237.49 205.74 0)
			(effects
				(font
					(size 1.27 1.27)
					(thickness 0.15)
				)
				(justify left bottom)
				(hide yes)
			)
		)
		(property "Description" "SMT test point"
			(at 219.71 193.04 0)
			(effects
				(font
					(size 1.27 1.27)
				)
				(hide yes)
			)
		)
		(property "MPN" ""
			(at 230.505 204.47 0)
			(effects
				(font
					(size 1.27 1.27)
					(thickness 0.15)
				)
				(justify left bottom)
				(hide yes)
			)
		)
		(property "Manufacturer" ""
			(at 230.505 199.39 0)
			(effects
				(font
					(size 1.27 1.27)
					(thickness 0.15)
				)
				(justify left bottom)
				(hide yes)
			)
		)
		(property "Author" "Antmicro"
			(at 229.87 201.93 0)
			(effects
				(font
					(size 1.27 1.27)
					(thickness 0.15)
				)
				(justify left bottom)
				(hide yes)
			)
		)
		(property "License" "Apache-2.0"
			(at 229.87 204.47 0)
			(effects
				(font
					(size 1.27 1.27)
					(thickness 0.15)
				)
				(justify left bottom)
				(hide yes)
			)
		)
		(pin "1"
		)
		(instances
			(project "jetson-agx-thor-baseboard"
				(path ""
					(reference "TP121")
					(unit 1)
				)
			)
		)
	)
	(symbol
		(lib_id "antmicropower:GND")
		(at 215.9 278.13 0)
		(unit 1)
		(exclude_from_sim no)
		(in_bom yes)
		(on_board yes)
		(dnp no)
		(property "Reference" "#PWR0563"
			(at 224.79 280.67 0)
			(effects
				(font
					(size 1.27 1.27)
					(thickness 0.15)
				)
				(justify left bottom)
				(hide yes)
			)
		)
		(property "Value" "GND"
			(at 215.9 281.94 0)
			(effects
				(font
					(size 1.27 1.27)
					(thickness 0.15)
				)
			)
		)
		(property "Footprint" ""
			(at 224.79 285.75 0)
			(effects
				(font
					(size 1.27 1.27)
					(thickness 0.15)
				)
				(justify left bottom)
				(hide yes)
			)
		)
		(property "Datasheet" ""
			(at 224.79 290.83 0)
			(effects
				(font
					(size 1.27 1.27)
					(thickness 0.15)
				)
				(justify left bottom)
				(hide yes)
			)
		)
		(property "Description" ""
			(at 215.9 278.13 0)
			(effects
				(font
					(size 1.27 1.27)
				)
				(hide yes)
			)
		)
		(property "Author" "Antmicro"
			(at 224.79 285.75 0)
			(effects
				(font
					(size 1.27 1.27)
					(thickness 0.15)
				)
				(justify left bottom)
				(hide yes)
			)
		)
		(property "License" "Apache-2.0"
			(at 224.79 288.29 0)
			(effects
				(font
					(size 1.27 1.27)
					(thickness 0.15)
				)
				(justify left bottom)
				(hide yes)
			)
		)
		(pin "1"
		)
		(instances
			(project "jetson-agx-thor-baseboard"
				(path ""
					(reference "#PWR0563")
					(unit 1)
				)
			)
		)
	)
	(symbol
		(lib_id "antmicroCapacitors0402:C_10u_0402")
		(at 106.68 48.26 90)
		(unit 1)
		(exclude_from_sim no)
		(in_bom yes)
		(on_board yes)
		(dnp no)
		(property "Reference" "C3"
			(at 109.22 44.4436 90)
			(effects
				(font
					(size 1.27 1.27)
					(thickness 0.15)
				)
				(justify right)
			)
		)
		(property "Value" "C_10u_0402"
			(at 116.84 27.94 0)
			(effects
				(font
					(size 1.27 1.27)
					(thickness 0.15)
				)
				(justify left bottom)
				(hide yes)
			)
		)
		(property "Footprint" "antmicro-footprints:C_0402_1005Metric"
			(at 119.38 27.94 0)
			(effects
				(font
					(size 1.27 1.27)
					(thickness 0.15)
				)
				(justify left bottom)
				(hide yes)
			)
		)
		(property "Datasheet" "https://www.yageo.com/en/Chart/Download/pdf/CC0402MRX5R5BB106"
			(at 121.92 27.94 0)
			(effects
				(font
					(size 1.27 1.27)
					(thickness 0.15)
				)
				(justify left bottom)
				(hide yes)
			)
		)
		(property "Description" "SMD Multilayer Ceramic Capacitor, 10 µF, 6.3 V, 0402 [1005 Metric], ± 20%, X5R, CC Series"
			(at 106.68 48.26 0)
			(effects
				(font
					(size 1.27 1.27)
				)
				(hide yes)
			)
		)
		(property "MPN" "CC0402MRX5R5BB106"
			(at 124.46 27.94 0)
			(effects
				(font
					(size 1.27 1.27)
					(thickness 0.15)
				)
				(justify left bottom)
				(hide yes)
			)
		)
		(property "Manufacturer" "YAGEO"
			(at 127 27.94 0)
			(effects
				(font
					(size 1.27 1.27)
					(thickness 0.15)
				)
				(justify left bottom)
				(hide yes)
			)
		)
		(property "License" "Apache-2.0"
			(at 129.54 27.94 0)
			(effects
				(font
					(size 1.27 1.27)
					(thickness 0.15)
				)
				(justify left bottom)
				(hide yes)
			)
		)
		(property "Author" "Antmicro"
			(at 132.08 27.94 0)
			(effects
				(font
					(size 1.27 1.27)
					(thickness 0.15)
				)
				(justify left bottom)
				(hide yes)
			)
		)
		(property "Val" "10u"
			(at 109.22 46.9836 90)
			(effects
				(font
					(size 1.27 1.27)
					(thickness 0.15)
				)
				(justify right)
			)
		)
		(property "Voltage" ""
			(at 134.62 27.94 0)
			(effects
				(font
					(size 1.27 1.27)
				)
				(justify left bottom)
				(hide yes)
			)
		)
		(property "Dielectric" "template_dielectric"
			(at 137.16 27.94 0)
			(effects
				(font
					(size 1.27 1.27)
				)
				(justify left bottom)
				(hide yes)
			)
		)
		(pin "1"
		)
		(pin "2"
		)
		(instances
			(project "jetson-agx-thor-baseboard"
				(path ""
					(reference "C3")
					(unit 1)
				)
			)
		)
	)
	(symbol
		(lib_id "antmicroResistors0402:R_49k9_0402")
		(at 97.79 173.99 90)
		(unit 1)
		(exclude_from_sim no)
		(in_bom yes)
		(on_board yes)
		(dnp no)
		(fields_autoplaced yes)
		(property "Reference" "R296"
			(at 100.33 170.18 90)
			(effects
				(font
					(size 1.27 1.27)
					(thickness 0.15)
				)
				(justify right)
			)
		)
		(property "Value" "R_49k9_0402"
			(at 110.49 153.67 0)
			(effects
				(font
					(size 1.27 1.27)
					(thickness 0.15)
				)
				(justify left bottom)
				(hide yes)
			)
		)
		(property "Footprint" "antmicro-footprints:R_0402_1005Metric"
			(at 113.03 153.67 0)
			(effects
				(font
					(size 1.27 1.27)
					(thickness 0.15)
				)
				(justify left bottom)
				(hide yes)
			)
		)
		(property "Datasheet" "https://www.bourns.com/docs/product-datasheets/cr.pdf"
			(at 115.57 153.67 0)
			(effects
				(font
					(size 1.27 1.27)
					(thickness 0.15)
				)
				(justify left bottom)
				(hide yes)
			)
		)
		(property "Description" "SMD Chip Resistor, 49.9 kohm, ± 1%, 63 mW, 0402 [1005 Metric], Thick Film, General Purpose"
			(at 128.27 153.67 0)
			(effects
				(font
					(size 1.27 1.27)
				)
				(justify left bottom)
				(hide yes)
			)
		)
		(property "MPN" "CR0402-FX-4992GLF"
			(at 118.11 153.67 0)
			(effects
				(font
					(size 1.27 1.27)
					(thickness 0.15)
				)
				(justify left bottom)
				(hide yes)
			)
		)
		(property "Manufacturer" "Bourns"
			(at 120.65 153.67 0)
			(effects
				(font
					(size 1.27 1.27)
					(thickness 0.15)
				)
				(justify left bottom)
				(hide yes)
			)
		)
		(property "License" "Apache-2.0"
			(at 123.19 153.67 0)
			(effects
				(font
					(size 1.27 1.27)
					(thickness 0.15)
				)
				(justify left bottom)
				(hide yes)
			)
		)
		(property "Author" "Antmicro"
			(at 125.73 153.67 0)
			(effects
				(font
					(size 1.27 1.27)
					(thickness 0.15)
				)
				(justify left bottom)
				(hide yes)
			)
		)
		(property "Val" "49k9"
			(at 100.33 172.72 90)
			(effects
				(font
					(size 1.27 1.27)
					(thickness 0.15)
				)
				(justify right)
			)
		)
		(property "Tolerance" "1%"
			(at 107.95 153.67 0)
			(effects
				(font
					(size 1.27 1.27)
				)
				(justify left bottom)
				(hide yes)
			)
		)
		(pin "1"
		)
		(pin "2"
		)
		(instances
			(project "jetson-agx-thor-baseboard"
				(path ""
					(reference "R296")
					(unit 1)
				)
			)
		)
	)
	(symbol
		(lib_id "antmicroResistors0402:R_10k_0402")
		(at 236.22 184.15 90)
		(unit 1)
		(exclude_from_sim no)
		(in_bom yes)
		(on_board yes)
		(dnp no)
		(property "Reference" "R304"
			(at 237.49 180.34 90)
			(effects
				(font
					(size 1.27 1.27)
					(thickness 0.15)
				)
				(justify right)
			)
		)
		(property "Value" "R_10k_0402"
			(at 248.92 163.83 0)
			(effects
				(font
					(size 1.27 1.27)
					(thickness 0.15)
				)
				(justify left bottom)
				(hide yes)
			)
		)
		(property "Footprint" "antmicro-footprints:R_0402_1005Metric"
			(at 251.46 163.83 0)
			(effects
				(font
					(size 1.27 1.27)
					(thickness 0.15)
				)
				(justify left bottom)
				(hide yes)
			)
		)
		(property "Datasheet" "https://www.bourns.com/docs/product-datasheets/cr.pdf"
			(at 254 163.83 0)
			(effects
				(font
					(size 1.27 1.27)
					(thickness 0.15)
				)
				(justify left bottom)
				(hide yes)
			)
		)
		(property "Description" "SMD Chip Resistor, 10 kohm, ± 1%, 62.5 mW, 0402 [1005 Metric], Thick Film, General Purpose"
			(at 236.22 184.15 0)
			(effects
				(font
					(size 1.27 1.27)
				)
				(hide yes)
			)
		)
		(property "MPN" "CR0402-FX-1002GLF"
			(at 256.54 163.83 0)
			(effects
				(font
					(size 1.27 1.27)
					(thickness 0.15)
				)
				(justify left bottom)
				(hide yes)
			)
		)
		(property "Manufacturer" "Bourns"
			(at 259.08 163.83 0)
			(effects
				(font
					(size 1.27 1.27)
					(thickness 0.15)
				)
				(justify left bottom)
				(hide yes)
			)
		)
		(property "License" "Apache-2.0"
			(at 261.62 163.83 0)
			(effects
				(font
					(size 1.27 1.27)
					(thickness 0.15)
				)
				(justify left bottom)
				(hide yes)
			)
		)
		(property "Author" "Antmicro"
			(at 264.16 163.83 0)
			(effects
				(font
					(size 1.27 1.27)
					(thickness 0.15)
				)
				(justify left bottom)
				(hide yes)
			)
		)
		(property "Val" "10k"
			(at 237.49 182.88 90)
			(effects
				(font
					(size 1.27 1.27)
					(thickness 0.15)
				)
				(justify right)
			)
		)
		(property "Tolerance" "1%"
			(at 246.38 163.83 0)
			(effects
				(font
					(size 1.27 1.27)
				)
				(justify left bottom)
				(hide yes)
			)
		)
		(pin "1"
		)
		(pin "2"
		)
		(instances
			(project "jetson-agx-thor-baseboard"
				(path ""
					(reference "R304")
					(unit 1)
				)
			)
		)
	)
	(symbol
		(lib_id "antmicroPushbuttonSwitches:SW_KMR211NGLFS_SMD")
		(at 85.09 113.03 270)
		(mirror x)
		(unit 1)
		(exclude_from_sim no)
		(in_bom yes)
		(on_board yes)
		(dnp no)
		(property "Reference" "S1"
			(at 88.265 109.22 90)
			(effects
				(font
					(size 1.27 1.27)
				)
				(justify left)
			)
		)
		(property "Value" "SW_KMR211NGLFS_SMD"
			(at 77.47 87.63 0)
			(effects
				(font
					(size 1.27 1.27)
					(thickness 0.15)
				)
				(justify left bottom)
				(hide yes)
			)
		)
		(property "Footprint" "antmicro-footprints:SW_KMR211NGLFS_SMD"
			(at 74.93 87.63 0)
			(effects
				(font
					(size 1.27 1.27)
					(thickness 0.15)
				)
				(justify left bottom)
				(hide yes)
			)
		)
		(property "Datasheet" "http://www.farnell.com/datasheets/2631211.pdf"
			(at 72.39 87.63 0)
			(effects
				(font
					(size 1.27 1.27)
					(thickness 0.15)
				)
				(justify left bottom)
				(hide yes)
			)
		)
		(property "Description" "Tactile Switch, KMR 2 Series, Top Actuated, Surface Mount, Oval Button, 120 gf, 50mA at 32VDC"
			(at 85.09 113.03 0)
			(effects
				(font
					(size 1.27 1.27)
				)
				(hide yes)
			)
		)
		(property "MPN" "KMR211NGLFS"
			(at 88.265 106.68 90)
			(effects
				(font
					(size 1.27 1.27)
					(thickness 0.15)
				)
				(justify left)
			)
		)
		(property "Manufacturer" "C&K"
			(at 69.85 87.63 0)
			(effects
				(font
					(size 1.27 1.27)
					(thickness 0.15)
				)
				(justify left bottom)
				(hide yes)
			)
		)
		(property "Author" "Antmicro"
			(at 67.31 87.63 0)
			(effects
				(font
					(size 1.27 1.27)
					(thickness 0.15)
				)
				(justify left bottom)
				(hide yes)
			)
		)
		(property "License" "Apache-2.0"
			(at 64.77 87.63 0)
			(effects
				(font
					(size 1.27 1.27)
					(thickness 0.15)
				)
				(justify left bottom)
				(hide yes)
			)
		)
		(pin "1"
		)
		(pin "2"
		)
		(pin "3"
		)
		(pin "4"
		)
		(instances
			(project "jetson-agx-thor-baseboard"
				(path ""
					(reference "S1")
					(unit 1)
				)
			)
		)
	)
	(symbol
		(lib_id "antmicroCapacitors0402:C_1u_25V_0402")
		(at 195.58 38.1 90)
		(unit 1)
		(exclude_from_sim no)
		(in_bom yes)
		(on_board yes)
		(dnp no)
		(property "Reference" "C359"
			(at 197.485 33.02 90)
			(effects
				(font
					(size 1.27 1.27)
					(thickness 0.15)
				)
				(justify right)
			)
		)
		(property "Value" "C_1u_25V_0402"
			(at 205.74 17.78 0)
			(effects
				(font
					(size 1.27 1.27)
					(thickness 0.15)
				)
				(justify left bottom)
				(hide yes)
			)
		)
		(property "Footprint" "antmicro-footprints:C_0402_1005Metric"
			(at 208.28 17.78 0)
			(effects
				(font
					(size 1.27 1.27)
					(thickness 0.15)
				)
				(justify left bottom)
				(hide yes)
			)
		)
		(property "Datasheet" "https://www.murata.com/products/productdetail?partno=GRM155R61E105KE11%23"
			(at 210.82 17.78 0)
			(effects
				(font
					(size 1.27 1.27)
					(thickness 0.15)
				)
				(justify left bottom)
				(hide yes)
			)
		)
		(property "Description" "SMD Multilayer Ceramic Capacitor, 1 µF, 25 V, 0402 [1005 Metric], ± 10%, X5R, GRM Series"
			(at 228.6 17.78 0)
			(effects
				(font
					(size 1.27 1.27)
				)
				(justify left bottom)
				(hide yes)
			)
		)
		(property "MPN" "GRM155R61E105KE11J"
			(at 213.36 17.78 0)
			(effects
				(font
					(size 1.27 1.27)
					(thickness 0.15)
				)
				(justify left bottom)
				(hide yes)
			)
		)
		(property "Manufacturer" "Murata"
			(at 215.9 17.78 0)
			(effects
				(font
					(size 1.27 1.27)
					(thickness 0.15)
				)
				(justify left bottom)
				(hide yes)
			)
		)
		(property "License" "Apache-2.0"
			(at 218.44 17.78 0)
			(effects
				(font
					(size 1.27 1.27)
					(thickness 0.15)
				)
				(justify left bottom)
				(hide yes)
			)
		)
		(property "Author" "Antmicro"
			(at 220.98 17.78 0)
			(effects
				(font
					(size 1.27 1.27)
					(thickness 0.15)
				)
				(justify left bottom)
				(hide yes)
			)
		)
		(property "Val" "1u"
			(at 197.485 35.56 90)
			(effects
				(font
					(size 1.27 1.27)
					(thickness 0.15)
				)
				(justify right)
			)
		)
		(property "Voltage" "25V"
			(at 197.485 38.0999 90)
			(effects
				(font
					(size 1.27 1.27)
				)
				(justify right)
			)
		)
		(property "Dielectric" "X5R"
			(at 226.06 17.78 0)
			(effects
				(font
					(size 1.27 1.27)
				)
				(justify left bottom)
				(hide yes)
			)
		)
		(pin "1"
		)
		(pin "2"
		)
		(instances
			(project "jetson-agx-thor-baseboard"
				(path ""
					(reference "C359")
					(unit 1)
				)
			)
		)
	)
	(symbol
		(lib_id "antmicropower:VCC")
		(at 265.43 30.48 0)
		(mirror y)
		(unit 1)
		(exclude_from_sim no)
		(in_bom yes)
		(on_board yes)
		(dnp no)
		(property "Reference" "#PWR038"
			(at 265.43 34.29 0)
			(effects
				(font
					(size 1.27 1.27)
				)
				(hide yes)
			)
		)
		(property "Value" "SYS_VIN_HV"
			(at 260.096 26.162 0)
			(effects
				(font
					(size 1.27 1.27)
				)
				(justify right)
			)
		)
		(property "Footprint" ""
			(at 265.43 30.48 0)
			(effects
				(font
					(size 1.27 1.27)
				)
				(hide yes)
			)
		)
		(property "Datasheet" ""
			(at 265.43 30.48 0)
			(effects
				(font
					(size 1.27 1.27)
				)
				(hide yes)
			)
		)
		(property "Description" ""
			(at 265.43 30.48 0)
			(effects
				(font
					(size 1.27 1.27)
				)
				(hide yes)
			)
		)
		(pin "1"
		)
		(instances
			(project "jetson-agx-thor-baseboard"
				(path ""
					(reference "#PWR038")
					(unit 1)
				)
			)
		)
	)
	(symbol
		(lib_id "antmicroCapacitors0402:C_100n_0402")
		(at 193.04 232.41 270)
		(mirror x)
		(unit 1)
		(exclude_from_sim no)
		(in_bom yes)
		(on_board yes)
		(dnp no)
		(property "Reference" "C41"
			(at 191.262 228.6 90)
			(effects
				(font
					(size 1.27 1.27)
					(thickness 0.15)
				)
				(justify right)
			)
		)
		(property "Value" "C_100n_0402"
			(at 182.88 212.09 0)
			(effects
				(font
					(size 1.27 1.27)
					(thickness 0.15)
				)
				(justify left bottom)
				(hide yes)
			)
		)
		(property "Footprint" "antmicro-footprints:C_0402_1005Metric"
			(at 180.34 212.09 0)
			(effects
				(font
					(size 1.27 1.27)
					(thickness 0.15)
				)
				(justify left bottom)
				(hide yes)
			)
		)
		(property "Datasheet" "https://www.murata.com/products/productdetail?partno=GRM155R61H104KE14%23"
			(at 177.8 212.09 0)
			(effects
				(font
					(size 1.27 1.27)
					(thickness 0.15)
				)
				(justify left bottom)
				(hide yes)
			)
		)
		(property "Description" "SMD Multilayer Ceramic Capacitor, 0.1 µF, 50 V, 0402 [1005 Metric], ± 10%, X5R, GRM Series"
			(at 160.02 212.09 0)
			(effects
				(font
					(size 1.27 1.27)
				)
				(justify left bottom)
				(hide yes)
			)
		)
		(property "MPN" "GRM155R61H104KE14D"
			(at 175.26 212.09 0)
			(effects
				(font
					(size 1.27 1.27)
					(thickness 0.15)
				)
				(justify left bottom)
				(hide yes)
			)
		)
		(property "Manufacturer" "Murata"
			(at 172.72 212.09 0)
			(effects
				(font
					(size 1.27 1.27)
					(thickness 0.15)
				)
				(justify left bottom)
				(hide yes)
			)
		)
		(property "License" "Apache-2.0"
			(at 170.18 212.09 0)
			(effects
				(font
					(size 1.27 1.27)
					(thickness 0.15)
				)
				(justify left bottom)
				(hide yes)
			)
		)
		(property "Author" "Antmicro"
			(at 167.64 212.09 0)
			(effects
				(font
					(size 1.27 1.27)
					(thickness 0.15)
				)
				(justify left bottom)
				(hide yes)
			)
		)
		(property "Val" "100n"
			(at 191.262 231.14 90)
			(effects
				(font
					(size 1.27 1.27)
					(thickness 0.15)
				)
				(justify right)
			)
		)
		(property "Voltage" "50V"
			(at 165.1 212.09 0)
			(effects
				(font
					(size 1.27 1.27)
				)
				(justify left bottom)
				(hide yes)
			)
		)
		(property "Dielectric" "X5R"
			(at 162.56 212.09 0)
			(effects
				(font
					(size 1.27 1.27)
				)
				(justify left bottom)
				(hide yes)
			)
		)
		(pin "1"
		)
		(pin "2"
		)
		(instances
			(project ""
				(path ""
					(reference "C41")
					(unit 1)
				)
			)
		)
	)
	(symbol
		(lib_id "antmicroResistors0402:R_0R_0402")
		(at 209.55 190.5 0)
		(unit 1)
		(exclude_from_sim no)
		(in_bom yes)
		(on_board yes)
		(dnp no)
		(property "Reference" "R302"
			(at 207.645 189.23 0)
			(effects
				(font
					(size 1.27 1.27)
					(thickness 0.15)
				)
			)
		)
		(property "Value" "R_0R_0402"
			(at 229.87 203.2 0)
			(effects
				(font
					(size 1.27 1.27)
					(thickness 0.15)
				)
				(justify left bottom)
				(hide yes)
			)
		)
		(property "Footprint" "antmicro-footprints:R_0402_1005Metric"
			(at 229.87 205.74 0)
			(effects
				(font
					(size 1.27 1.27)
					(thickness 0.15)
				)
				(justify left bottom)
				(hide yes)
			)
		)
		(property "Datasheet" "https://industrial.panasonic.com/cdbs/www-data/pdf/RDA0000/AOA0000C301.pdf"
			(at 229.87 208.28 0)
			(effects
				(font
					(size 1.27 1.27)
					(thickness 0.15)
				)
				(justify left bottom)
				(hide yes)
			)
		)
		(property "Description" "SMD Chip Resistor, Jumper, 0 ohm, 100 mW, 0402 [1005 Metric], Thick Film, General Purpose"
			(at 209.55 190.5 0)
			(effects
				(font
					(size 1.27 1.27)
				)
				(hide yes)
			)
		)
		(property "MPN" "ERJ2GE0R00X"
			(at 229.87 210.82 0)
			(effects
				(font
					(size 1.27 1.27)
					(thickness 0.15)
				)
				(justify left bottom)
				(hide yes)
			)
		)
		(property "Manufacturer" "Panasonic"
			(at 229.87 213.36 0)
			(effects
				(font
					(size 1.27 1.27)
					(thickness 0.15)
				)
				(justify left bottom)
				(hide yes)
			)
		)
		(property "License" "Apache-2.0"
			(at 229.87 215.9 0)
			(effects
				(font
					(size 1.27 1.27)
					(thickness 0.15)
				)
				(justify left bottom)
				(hide yes)
			)
		)
		(property "Author" "Antmicro"
			(at 229.87 218.44 0)
			(effects
				(font
					(size 1.27 1.27)
					(thickness 0.15)
				)
				(justify left bottom)
				(hide yes)
			)
		)
		(property "Val" "0R"
			(at 215.9 189.23 0)
			(effects
				(font
					(size 1.27 1.27)
					(thickness 0.15)
				)
			)
		)
		(property "Tolerance" "~"
			(at 229.87 200.66 0)
			(effects
				(font
					(size 1.27 1.27)
				)
				(justify left bottom)
				(hide yes)
			)
		)
		(property "Current" "1A"
			(at 229.87 220.98 0)
			(effects
				(font
					(size 1.27 1.27)
					(thickness 0.15)
				)
				(justify left bottom)
				(hide yes)
			)
		)
		(pin "2"
		)
		(pin "1"
		)
		(instances
			(project "jetson-agx-thor-baseboard"
				(path ""
					(reference "R302")
					(unit 1)
				)
			)
		)
	)
	(symbol
		(lib_id "antmicropower:GND")
		(at 189.23 92.71 0)
		(unit 1)
		(exclude_from_sim no)
		(in_bom yes)
		(on_board yes)
		(dnp no)
		(fields_autoplaced yes)
		(property "Reference" "#PWR040"
			(at 198.12 95.25 0)
			(effects
				(font
					(size 1.27 1.27)
					(thickness 0.15)
				)
				(justify left bottom)
				(hide yes)
			)
		)
		(property "Value" "GND"
			(at 189.23 97.79 0)
			(effects
				(font
					(size 1.27 1.27)
					(thickness 0.15)
				)
			)
		)
		(property "Footprint" ""
			(at 198.12 100.33 0)
			(effects
				(font
					(size 1.27 1.27)
					(thickness 0.15)
				)
				(justify left bottom)
				(hide yes)
			)
		)
		(property "Datasheet" ""
			(at 198.12 105.41 0)
			(effects
				(font
					(size 1.27 1.27)
					(thickness 0.15)
				)
				(justify left bottom)
				(hide yes)
			)
		)
		(property "Description" ""
			(at 189.23 92.71 0)
			(effects
				(font
					(size 1.27 1.27)
				)
				(hide yes)
			)
		)
		(property "Author" "Antmicro"
			(at 198.12 100.33 0)
			(effects
				(font
					(size 1.27 1.27)
					(thickness 0.15)
				)
				(justify left bottom)
				(hide yes)
			)
		)
		(property "License" "Apache-2.0"
			(at 198.12 102.87 0)
			(effects
				(font
					(size 1.27 1.27)
					(thickness 0.15)
				)
				(justify left bottom)
				(hide yes)
			)
		)
		(pin "1"
		)
		(instances
			(project "jetson-agx-thor-baseboard"
				(path ""
					(reference "#PWR040")
					(unit 1)
				)
			)
		)
	)
	(symbol
		(lib_id "antmicroCapacitors0402:C_100n_0402")
		(at 170.18 38.1 90)
		(unit 1)
		(exclude_from_sim no)
		(in_bom yes)
		(on_board yes)
		(dnp no)
		(fields_autoplaced yes)
		(property "Reference" "C18"
			(at 172.72 34.2836 90)
			(effects
				(font
					(size 1.27 1.27)
					(thickness 0.15)
				)
				(justify right)
			)
		)
		(property "Value" "C_100n_0402"
			(at 193.04 22.86 0)
			(effects
				(font
					(size 1.27 1.27)
					(thickness 0.15)
				)
				(justify left bottom)
				(hide yes)
			)
		)
		(property "Footprint" "antmicro-footprints:C_0402_1005Metric"
			(at 195.58 22.86 0)
			(effects
				(font
					(size 1.27 1.27)
					(thickness 0.15)
				)
				(justify left bottom)
				(hide yes)
			)
		)
		(property "Datasheet" "https://www.murata.com/products/productdetail?partno=GRM155R61H104KE14%23"
			(at 198.12 22.86 0)
			(effects
				(font
					(size 1.27 1.27)
					(thickness 0.15)
				)
				(justify left bottom)
				(hide yes)
			)
		)
		(property "Description" "SMD Multilayer Ceramic Capacitor, 0.1 µF, 50 V, 0402 [1005 Metric], ± 10%, X5R, GRM Series"
			(at 170.18 38.1 0)
			(effects
				(font
					(size 1.27 1.27)
				)
				(hide yes)
			)
		)
		(property "MPN" "GRM155R61H104KE14D"
			(at 200.66 22.86 0)
			(effects
				(font
					(size 1.27 1.27)
					(thickness 0.15)
				)
				(justify left bottom)
				(hide yes)
			)
		)
		(property "Val" "100n"
			(at 172.72 36.8236 90)
			(effects
				(font
					(size 1.27 1.27)
					(thickness 0.15)
				)
				(justify right)
			)
		)
		(property "Voltage" "50V"
			(at 180.34 22.86 0)
			(effects
				(font
					(size 1.27 1.27)
					(thickness 0.15)
				)
				(justify left bottom)
				(hide yes)
			)
		)
		(property "Dielectric" "X5R"
			(at 182.88 22.86 0)
			(effects
				(font
					(size 1.27 1.27)
					(thickness 0.15)
				)
				(justify left bottom)
				(hide yes)
			)
		)
		(property "Manufacturer" "Murata"
			(at 185.42 22.86 0)
			(effects
				(font
					(size 1.27 1.27)
					(thickness 0.15)
				)
				(justify left bottom)
				(hide yes)
			)
		)
		(property "License" "Apache-2.0"
			(at 187.96 22.86 0)
			(effects
				(font
					(size 1.27 1.27)
					(thickness 0.15)
				)
				(justify left bottom)
				(hide yes)
			)
		)
		(property "Author" "Antmicro"
			(at 190.5 22.86 0)
			(effects
				(font
					(size 1.27 1.27)
					(thickness 0.15)
				)
				(justify left bottom)
				(hide yes)
			)
		)
		(pin "1"
		)
		(pin "2"
		)
		(instances
			(project "jetson-agx-thor-baseboard"
				(path ""
					(reference "C18")
					(unit 1)
				)
			)
		)
	)
	(symbol
		(lib_id "antmicropower:GND")
		(at 54.61 106.68 0)
		(mirror y)
		(unit 1)
		(exclude_from_sim no)
		(in_bom yes)
		(on_board yes)
		(dnp no)
		(property "Reference" "#PWR063"
			(at 54.61 113.03 0)
			(effects
				(font
					(size 1.27 1.27)
				)
				(justify left bottom)
				(hide yes)
			)
		)
		(property "Value" "GND"
			(at 54.61 110.49 0)
			(effects
				(font
					(size 1.27 1.27)
					(thickness 0.15)
				)
			)
		)
		(property "Footprint" ""
			(at 45.72 114.3 0)
			(effects
				(font
					(size 1.27 1.27)
					(thickness 0.15)
				)
				(justify left bottom)
				(hide yes)
			)
		)
		(property "Datasheet" ""
			(at 45.72 119.38 0)
			(effects
				(font
					(size 1.27 1.27)
					(thickness 0.15)
				)
				(justify left bottom)
				(hide yes)
			)
		)
		(property "Description" ""
			(at 54.61 106.68 0)
			(effects
				(font
					(size 1.27 1.27)
				)
				(hide yes)
			)
		)
		(property "Author" "Antmicro"
			(at 45.72 114.3 0)
			(effects
				(font
					(size 1.27 1.27)
					(thickness 0.15)
				)
				(justify left bottom)
				(hide yes)
			)
		)
		(property "License" "Apache-2.0"
			(at 45.72 116.84 0)
			(effects
				(font
					(size 1.27 1.27)
					(thickness 0.15)
				)
				(justify left bottom)
				(hide yes)
			)
		)
		(pin "1"
		)
		(instances
			(project "jetson-agx-thor-baseboard"
				(path ""
					(reference "#PWR063")
					(unit 1)
				)
			)
		)
	)
	(symbol
		(lib_id "antmicropower:+3V3_AON")
		(at 179.07 175.26 0)
		(unit 1)
		(exclude_from_sim no)
		(in_bom yes)
		(on_board yes)
		(dnp no)
		(fields_autoplaced yes)
		(property "Reference" "#PWR0115"
			(at 179.07 179.07 0)
			(effects
				(font
					(size 1.27 1.27)
				)
				(hide yes)
			)
		)
		(property "Value" "+5V_AON"
			(at 179.07 170.18 0)
			(effects
				(font
					(size 1.27 1.27)
				)
			)
		)
		(property "Footprint" ""
			(at 179.07 175.26 0)
			(effects
				(font
					(size 1.27 1.27)
				)
				(hide yes)
			)
		)
		(property "Datasheet" ""
			(at 179.07 175.26 0)
			(effects
				(font
					(size 1.27 1.27)
				)
				(hide yes)
			)
		)
		(property "Description" ""
			(at 179.07 175.26 0)
			(effects
				(font
					(size 1.27 1.27)
				)
				(hide yes)
			)
		)
		(pin "1"
		)
		(instances
			(project "jetson-agx-thor-baseboard"
				(path ""
					(reference "#PWR0115")
					(unit 1)
				)
			)
		)
	)
	(symbol
		(lib_id "antmicropower:GND")
		(at 76.2 251.46 0)
		(unit 1)
		(exclude_from_sim no)
		(in_bom yes)
		(on_board yes)
		(dnp no)
		(property "Reference" "#PWR0578"
			(at 76.2 257.81 0)
			(effects
				(font
					(size 1.27 1.27)
				)
				(justify left bottom)
				(hide yes)
			)
		)
		(property "Value" "GND"
			(at 76.2 255.27 0)
			(effects
				(font
					(size 1.27 1.27)
					(thickness 0.15)
				)
			)
		)
		(property "Footprint" ""
			(at 85.09 259.08 0)
			(effects
				(font
					(size 1.27 1.27)
					(thickness 0.15)
				)
				(justify left bottom)
				(hide yes)
			)
		)
		(property "Datasheet" ""
			(at 85.09 264.16 0)
			(effects
				(font
					(size 1.27 1.27)
					(thickness 0.15)
				)
				(justify left bottom)
				(hide yes)
			)
		)
		(property "Description" ""
			(at 76.2 251.46 0)
			(effects
				(font
					(size 1.27 1.27)
				)
				(hide yes)
			)
		)
		(property "Author" "Antmicro"
			(at 85.09 259.08 0)
			(effects
				(font
					(size 1.27 1.27)
					(thickness 0.15)
				)
				(justify left bottom)
				(hide yes)
			)
		)
		(property "License" "Apache-2.0"
			(at 85.09 261.62 0)
			(effects
				(font
					(size 1.27 1.27)
					(thickness 0.15)
				)
				(justify left bottom)
				(hide yes)
			)
		)
		(pin "1"
		)
		(instances
			(project "jetson-agx-thor-baseboard"
				(path ""
					(reference "#PWR0578")
					(unit 1)
				)
			)
		)
	)
	(symbol
		(lib_id "antmicroCapacitors0603:C_22u_16V_0603")
		(at 133.35 38.1 90)
		(unit 1)
		(exclude_from_sim no)
		(in_bom yes)
		(on_board yes)
		(dnp no)
		(property "Reference" "C22"
			(at 135.89 34.2836 90)
			(effects
				(font
					(size 1.27 1.27)
					(thickness 0.15)
				)
				(justify right)
			)
		)
		(property "Value" "C_22u_16V_0603"
			(at 143.51 17.78 0)
			(effects
				(font
					(size 1.27 1.27)
					(thickness 0.15)
				)
				(justify left bottom)
				(hide yes)
			)
		)
		(property "Footprint" "antmicro-footprints:C_0603_1608Metric_EIA"
			(at 146.05 17.78 0)
			(effects
				(font
					(size 1.27 1.27)
					(thickness 0.15)
				)
				(justify left bottom)
				(hide yes)
			)
		)
		(property "Datasheet" "https://product.samsungsem.com/mlcc/CL10A226MO7JZN.do"
			(at 148.59 17.78 0)
			(effects
				(font
					(size 1.27 1.27)
					(thickness 0.15)
				)
				(justify left bottom)
				(hide yes)
			)
		)
		(property "Description" "SMD Multilayer Ceramic Capacitor"
			(at 133.35 38.1 0)
			(effects
				(font
					(size 1.27 1.27)
				)
				(hide yes)
			)
		)
		(property "MPN" "CL10A226MO7JZNC"
			(at 151.13 17.78 0)
			(effects
				(font
					(size 1.27 1.27)
					(thickness 0.15)
				)
				(justify left bottom)
				(hide yes)
			)
		)
		(property "Manufacturer" "Samsung Electro-Mechanics"
			(at 153.67 17.78 0)
			(effects
				(font
					(size 1.27 1.27)
					(thickness 0.15)
				)
				(justify left bottom)
				(hide yes)
			)
		)
		(property "License" "Apache-2.0"
			(at 156.21 17.78 0)
			(effects
				(font
					(size 1.27 1.27)
					(thickness 0.15)
				)
				(justify left bottom)
				(hide yes)
			)
		)
		(property "Author" "Antmicro"
			(at 158.75 17.78 0)
			(effects
				(font
					(size 1.27 1.27)
					(thickness 0.15)
				)
				(justify left bottom)
				(hide yes)
			)
		)
		(property "Val" "22u"
			(at 135.89 36.8236 90)
			(effects
				(font
					(size 1.27 1.27)
					(thickness 0.15)
				)
				(justify right)
			)
		)
		(property "Voltage" "16V"
			(at 161.29 17.78 0)
			(effects
				(font
					(size 1.27 1.27)
				)
				(justify left bottom)
				(hide yes)
			)
		)
		(property "Dielectric" "X7R"
			(at 163.83 17.78 0)
			(effects
				(font
					(size 1.27 1.27)
				)
				(justify left bottom)
				(hide yes)
			)
		)
		(property "Public" "False"
			(at 166.37 17.78 0)
			(effects
				(font
					(size 1.27 1.27)
				)
				(justify left bottom)
				(hide yes)
			)
		)
		(pin "1"
		)
		(pin "2"
		)
		(instances
			(project "jetson-agx-thor-baseboard"
				(path ""
					(reference "C22")
					(unit 1)
				)
			)
		)
	)
	(symbol
		(lib_id "antmicropower:GND")
		(at 375.92 228.6 0)
		(unit 1)
		(exclude_from_sim no)
		(in_bom yes)
		(on_board yes)
		(dnp no)
		(property "Reference" "#PWR0141"
			(at 375.92 234.95 0)
			(effects
				(font
					(size 1.27 1.27)
				)
				(justify left bottom)
				(hide yes)
			)
		)
		(property "Value" "GND"
			(at 375.92 232.41 0)
			(effects
				(font
					(size 1.27 1.27)
					(thickness 0.15)
				)
			)
		)
		(property "Footprint" ""
			(at 384.81 236.22 0)
			(effects
				(font
					(size 1.27 1.27)
					(thickness 0.15)
				)
				(justify left bottom)
				(hide yes)
			)
		)
		(property "Datasheet" ""
			(at 384.81 241.3 0)
			(effects
				(font
					(size 1.27 1.27)
					(thickness 0.15)
				)
				(justify left bottom)
				(hide yes)
			)
		)
		(property "Description" ""
			(at 375.92 228.6 0)
			(effects
				(font
					(size 1.27 1.27)
				)
				(hide yes)
			)
		)
		(property "Author" "Antmicro"
			(at 384.81 236.22 0)
			(effects
				(font
					(size 1.27 1.27)
					(thickness 0.15)
				)
				(justify left bottom)
				(hide yes)
			)
		)
		(property "License" "Apache-2.0"
			(at 384.81 238.76 0)
			(effects
				(font
					(size 1.27 1.27)
					(thickness 0.15)
				)
				(justify left bottom)
				(hide yes)
			)
		)
		(pin "1"
		)
		(instances
			(project "jetson-agx-thor-baseboard"
				(path ""
					(reference "#PWR0141")
					(unit 1)
				)
			)
		)
	)
	(symbol
		(lib_id "antmicroResistors0402:R_100k_0402")
		(at 290.83 162.56 90)
		(unit 1)
		(exclude_from_sim no)
		(in_bom yes)
		(on_board yes)
		(dnp no)
		(fields_autoplaced yes)
		(property "Reference" "R47"
			(at 293.37 158.75 90)
			(effects
				(font
					(size 1.27 1.27)
					(thickness 0.15)
				)
				(justify right)
			)
		)
		(property "Value" "R_100k_0402"
			(at 303.53 142.24 0)
			(effects
				(font
					(size 1.27 1.27)
					(thickness 0.15)
				)
				(justify left bottom)
				(hide yes)
			)
		)
		(property "Footprint" "antmicro-footprints:R_0402_1005Metric"
			(at 306.07 142.24 0)
			(effects
				(font
					(size 1.27 1.27)
					(thickness 0.15)
				)
				(justify left bottom)
				(hide yes)
			)
		)
		(property "Datasheet" "https://www.bourns.com/docs/product-datasheets/cr.pdf"
			(at 308.61 142.24 0)
			(effects
				(font
					(size 1.27 1.27)
					(thickness 0.15)
				)
				(justify left bottom)
				(hide yes)
			)
		)
		(property "Description" "SMD Chip Resistor, 100 kohm, ± 1%, 62.5 mW, 0402 [1005 Metric], Thick Film, General Purpose"
			(at 321.31 142.24 0)
			(effects
				(font
					(size 1.27 1.27)
				)
				(justify left bottom)
				(hide yes)
			)
		)
		(property "MPN" "CR0402-FX-1003GLF"
			(at 311.15 142.24 0)
			(effects
				(font
					(size 1.27 1.27)
					(thickness 0.15)
				)
				(justify left bottom)
				(hide yes)
			)
		)
		(property "Manufacturer" "Bourns"
			(at 313.69 142.24 0)
			(effects
				(font
					(size 1.27 1.27)
					(thickness 0.15)
				)
				(justify left bottom)
				(hide yes)
			)
		)
		(property "License" "Apache-2.0"
			(at 316.23 142.24 0)
			(effects
				(font
					(size 1.27 1.27)
					(thickness 0.15)
				)
				(justify left bottom)
				(hide yes)
			)
		)
		(property "Author" "Antmicro"
			(at 318.77 142.24 0)
			(effects
				(font
					(size 1.27 1.27)
					(thickness 0.15)
				)
				(justify left bottom)
				(hide yes)
			)
		)
		(property "Val" "100k"
			(at 293.37 161.29 90)
			(effects
				(font
					(size 1.27 1.27)
					(thickness 0.15)
				)
				(justify right)
			)
		)
		(property "Tolerance" "1%"
			(at 300.99 142.24 0)
			(effects
				(font
					(size 1.27 1.27)
				)
				(justify left bottom)
				(hide yes)
			)
		)
		(pin "1"
		)
		(pin "2"
		)
		(instances
			(project ""
				(path ""
					(reference "R47")
					(unit 1)
				)
			)
		)
	)
	(symbol
		(lib_id "antmicropower:+5V")
		(at 323.85 156.21 0)
		(unit 1)
		(exclude_from_sim no)
		(in_bom yes)
		(on_board yes)
		(dnp no)
		(property "Reference" "#PWR0659"
			(at 323.85 160.02 0)
			(effects
				(font
					(size 1.27 1.27)
				)
				(justify left bottom)
				(hide yes)
			)
		)
		(property "Value" "+5V_SOM"
			(at 321.31 152.146 0)
			(effects
				(font
					(size 1.27 1.27)
					(thickness 0.15)
				)
				(justify left)
			)
		)
		(property "Footprint" ""
			(at 339.09 163.83 0)
			(effects
				(font
					(size 1.27 1.27)
					(thickness 0.15)
				)
				(justify left bottom)
				(hide yes)
			)
		)
		(property "Datasheet" ""
			(at 339.09 166.37 0)
			(effects
				(font
					(size 1.27 1.27)
					(thickness 0.15)
				)
				(justify left bottom)
				(hide yes)
			)
		)
		(property "Description" ""
			(at 323.85 156.21 0)
			(effects
				(font
					(size 1.27 1.27)
				)
				(hide yes)
			)
		)
		(property "Author" "Antmicro"
			(at 339.09 163.83 0)
			(effects
				(font
					(size 1.27 1.27)
					(thickness 0.15)
				)
				(justify left bottom)
				(hide yes)
			)
		)
		(property "License" "Apache-2.0"
			(at 339.09 166.37 0)
			(effects
				(font
					(size 1.27 1.27)
					(thickness 0.15)
				)
				(justify left bottom)
				(hide yes)
			)
		)
		(pin "1"
		)
		(instances
			(project "jetson-agx-thor-baseboard"
				(path ""
					(reference "#PWR0659")
					(unit 1)
				)
			)
		)
	)
	(symbol
		(lib_id "antmicropower:VCC")
		(at 307.34 156.21 0)
		(mirror y)
		(unit 1)
		(exclude_from_sim no)
		(in_bom yes)
		(on_board yes)
		(dnp no)
		(property "Reference" "#PWR088"
			(at 307.34 160.02 0)
			(effects
				(font
					(size 1.27 1.27)
				)
				(hide yes)
			)
		)
		(property "Value" "SYS_VIN_HV"
			(at 302.006 151.892 0)
			(effects
				(font
					(size 1.27 1.27)
				)
				(justify right)
			)
		)
		(property "Footprint" ""
			(at 307.34 156.21 0)
			(effects
				(font
					(size 1.27 1.27)
				)
				(hide yes)
			)
		)
		(property "Datasheet" ""
			(at 307.34 156.21 0)
			(effects
				(font
					(size 1.27 1.27)
				)
				(hide yes)
			)
		)
		(property "Description" ""
			(at 307.34 156.21 0)
			(effects
				(font
					(size 1.27 1.27)
				)
				(hide yes)
			)
		)
		(pin "1"
		)
		(instances
			(project "jetson-agx-thor-baseboard"
				(path ""
					(reference "#PWR088")
					(unit 1)
				)
			)
		)
	)
	(symbol
		(lib_id "antmicroTVSDiodes:TPD1E0B04_XDFN-2")
		(at 363.22 85.09 270)
		(mirror x)
		(unit 1)
		(exclude_from_sim no)
		(in_bom yes)
		(on_board yes)
		(dnp no)
		(property "Reference" "D46"
			(at 361.696 72.39 90)
			(effects
				(font
					(size 1.27 1.27)
				)
				(justify left)
			)
		)
		(property "Value" "TPD1E0B04_XDFN-2"
			(at 353.06 69.85 0)
			(effects
				(font
					(size 1.27 1.27)
					(thickness 0.15)
				)
				(justify left bottom)
				(hide yes)
			)
		)
		(property "Footprint" "antmicro-footprints:XDFN-2_1x0.60mm"
			(at 358.14 69.85 0)
			(effects
				(font
					(size 1.27 1.27)
					(thickness 0.15)
				)
				(justify left bottom)
				(hide yes)
			)
		)
		(property "Datasheet" "https://www.ti.com/general/docs/suppproductinfo.tsp?distId=26&gotoUrl=https://www.ti.com/lit/gpn/tpd1e0b04"
			(at 355.6 69.85 0)
			(effects
				(font
					(size 1.27 1.27)
					(thickness 0.15)
				)
				(justify left bottom)
				(hide yes)
			)
		)
		(property "Description" "Bidirectional TVS, 8 kV,  XDFN-2, 3.6 V, 0.18 pF"
			(at 363.22 85.09 0)
			(effects
				(font
					(size 1.27 1.27)
				)
				(hide yes)
			)
		)
		(property "Manufacturer" "Texas Instruments"
			(at 350.52 69.85 0)
			(effects
				(font
					(size 1.27 1.27)
					(thickness 0.15)
				)
				(justify left bottom)
				(hide yes)
			)
		)
		(property "MPN" "TPD1E0B04DPYR"
			(at 361.696 74.93 90)
			(effects
				(font
					(size 1.27 1.27)
					(thickness 0.15)
				)
				(justify left)
			)
		)
		(property "Author" "Antmicro"
			(at 347.98 69.85 0)
			(effects
				(font
					(size 1.27 1.27)
					(thickness 0.15)
				)
				(justify left bottom)
				(hide yes)
			)
		)
		(property "License" "Apache-2.0"
			(at 345.44 69.85 0)
			(effects
				(font
					(size 1.27 1.27)
					(thickness 0.15)
				)
				(justify left bottom)
				(hide yes)
			)
		)
		(pin "1"
		)
		(pin "2"
		)
		(instances
			(project "jetson-agx-thor-baseboard"
				(path ""
					(reference "D46")
					(unit 1)
				)
			)
		)
	)
	(symbol
		(lib_id "antmicropower:+3V3_AON")
		(at 193.04 224.79 0)
		(mirror y)
		(unit 1)
		(exclude_from_sim no)
		(in_bom yes)
		(on_board yes)
		(dnp no)
		(property "Reference" "#PWR0158"
			(at 193.04 228.6 0)
			(effects
				(font
					(size 1.27 1.27)
				)
				(hide yes)
			)
		)
		(property "Value" "+3V3_AON"
			(at 193.04 220.98 0)
			(effects
				(font
					(size 1.27 1.27)
				)
			)
		)
		(property "Footprint" ""
			(at 193.04 224.79 0)
			(effects
				(font
					(size 1.27 1.27)
				)
				(hide yes)
			)
		)
		(property "Datasheet" ""
			(at 193.04 224.79 0)
			(effects
				(font
					(size 1.27 1.27)
				)
				(hide yes)
			)
		)
		(property "Description" ""
			(at 193.04 224.79 0)
			(effects
				(font
					(size 1.27 1.27)
				)
				(hide yes)
			)
		)
		(pin "1"
		)
		(instances
			(project "jetson-agx-thor-baseboard"
				(path ""
					(reference "#PWR0158")
					(unit 1)
				)
			)
		)
	)
	(symbol
		(lib_id "antmicroCapacitors0402:C_100n_0402")
		(at 96.52 160.02 90)
		(unit 1)
		(exclude_from_sim no)
		(in_bom no)
		(on_board yes)
		(dnp yes)
		(property "Reference" "C8"
			(at 99.06 156.2036 90)
			(effects
				(font
					(size 1.27 1.27)
					(thickness 0.15)
				)
				(justify right)
			)
		)
		(property "Value" "C_100n_0402"
			(at 106.68 139.7 0)
			(effects
				(font
					(size 1.27 1.27)
					(thickness 0.15)
				)
				(justify left bottom)
				(hide yes)
			)
		)
		(property "Footprint" "antmicro-footprints:C_0402_1005Metric"
			(at 109.22 139.7 0)
			(effects
				(font
					(size 1.27 1.27)
					(thickness 0.15)
				)
				(justify left bottom)
				(hide yes)
			)
		)
		(property "Datasheet" "https://www.murata.com/products/productdetail?partno=GRM155R61H104KE14%23"
			(at 111.76 139.7 0)
			(effects
				(font
					(size 1.27 1.27)
					(thickness 0.15)
				)
				(justify left bottom)
				(hide yes)
			)
		)
		(property "Description" "SMD Multilayer Ceramic Capacitor, 0.1 µF, 50 V, 0402 [1005 Metric], ± 10%, X5R, GRM Series"
			(at 96.52 160.02 0)
			(effects
				(font
					(size 1.27 1.27)
				)
				(hide yes)
			)
		)
		(property "MPN" "GRM155R61H104KE14D"
			(at 114.3 139.7 0)
			(effects
				(font
					(size 1.27 1.27)
					(thickness 0.15)
				)
				(justify left bottom)
				(hide yes)
			)
		)
		(property "Manufacturer" "Murata"
			(at 116.84 139.7 0)
			(effects
				(font
					(size 1.27 1.27)
					(thickness 0.15)
				)
				(justify left bottom)
				(hide yes)
			)
		)
		(property "License" "Apache-2.0"
			(at 119.38 139.7 0)
			(effects
				(font
					(size 1.27 1.27)
					(thickness 0.15)
				)
				(justify left bottom)
				(hide yes)
			)
		)
		(property "Author" "Antmicro"
			(at 121.92 139.7 0)
			(effects
				(font
					(size 1.27 1.27)
					(thickness 0.15)
				)
				(justify left bottom)
				(hide yes)
			)
		)
		(property "Val" "100n"
			(at 99.06 158.7436 90)
			(effects
				(font
					(size 1.27 1.27)
					(thickness 0.15)
				)
				(justify right)
			)
		)
		(property "Voltage" "50V"
			(at 124.46 139.7 0)
			(effects
				(font
					(size 1.27 1.27)
				)
				(justify left bottom)
				(hide yes)
			)
		)
		(property "Dielectric" "X5R"
			(at 127 139.7 0)
			(effects
				(font
					(size 1.27 1.27)
				)
				(justify left bottom)
				(hide yes)
			)
		)
		(property "Public" "False"
			(at 129.54 139.7 0)
			(effects
				(font
					(size 1.27 1.27)
				)
				(justify left bottom)
				(hide yes)
			)
		)
		(pin "1"
		)
		(pin "2"
		)
		(instances
			(project "jetson-agx-thor-baseboard"
				(path ""
					(reference "C8")
					(unit 1)
				)
			)
		)
	)
	(symbol
		(lib_id "antmicroTestPoints:TP_0.75mm_SMD")
		(at 269.24 73.66 0)
		(unit 1)
		(exclude_from_sim no)
		(in_bom no)
		(on_board yes)
		(dnp no)
		(property "Reference" "TP48"
			(at 274.32 73.66 0)
			(effects
				(font
					(size 1.27 1.27)
					(thickness 0.15)
				)
				(justify left)
			)
		)
		(property "Value" "TP_0.75mm_SMD"
			(at 279.4 77.47 0)
			(effects
				(font
					(size 1.27 1.27)
					(thickness 0.15)
				)
				(justify left bottom)
				(hide yes)
			)
		)
		(property "Footprint" "antmicro-footprints:TP_SMD_0.75mm"
			(at 279.4 80.01 0)
			(effects
				(font
					(size 1.27 1.27)
					(thickness 0.15)
				)
				(justify left bottom)
				(hide yes)
			)
		)
		(property "Datasheet" ""
			(at 287.02 86.36 0)
			(effects
				(font
					(size 1.27 1.27)
					(thickness 0.15)
				)
				(justify left bottom)
				(hide yes)
			)
		)
		(property "Description" "SMT test point"
			(at 269.24 73.66 0)
			(effects
				(font
					(size 1.27 1.27)
				)
				(hide yes)
			)
		)
		(property "MPN" ""
			(at 280.035 85.09 0)
			(effects
				(font
					(size 1.27 1.27)
					(thickness 0.15)
				)
				(justify left bottom)
				(hide yes)
			)
		)
		(property "Manufacturer" ""
			(at 280.035 80.01 0)
			(effects
				(font
					(size 1.27 1.27)
					(thickness 0.15)
				)
				(justify left bottom)
				(hide yes)
			)
		)
		(property "Author" "Antmicro"
			(at 279.4 82.55 0)
			(effects
				(font
					(size 1.27 1.27)
					(thickness 0.15)
				)
				(justify left bottom)
				(hide yes)
			)
		)
		(property "License" "Apache-2.0"
			(at 279.4 85.09 0)
			(effects
				(font
					(size 1.27 1.27)
					(thickness 0.15)
				)
				(justify left bottom)
				(hide yes)
			)
		)
		(pin "1"
		)
		(instances
			(project "jetson-agx-thor-baseboard"
				(path ""
					(reference "TP48")
					(unit 1)
				)
			)
		)
	)
	(symbol
		(lib_id "antmicroResistors0402:R_47k_0402")
		(at 182.88 199.39 90)
		(unit 1)
		(exclude_from_sim no)
		(in_bom yes)
		(on_board yes)
		(dnp no)
		(property "Reference" "R288"
			(at 181.61 195.58 90)
			(effects
				(font
					(size 1.27 1.27)
					(thickness 0.15)
				)
				(justify left)
			)
		)
		(property "Value" "R_47k_0402"
			(at 195.58 179.07 0)
			(effects
				(font
					(size 1.27 1.27)
					(thickness 0.15)
				)
				(justify left bottom)
				(hide yes)
			)
		)
		(property "Footprint" "antmicro-footprints:R_0402_1005Metric"
			(at 198.12 179.07 0)
			(effects
				(font
					(size 1.27 1.27)
					(thickness 0.15)
				)
				(justify left bottom)
				(hide yes)
			)
		)
		(property "Datasheet" "https://www.bourns.com/docs/product-datasheets/cr.pdf"
			(at 200.66 179.07 0)
			(effects
				(font
					(size 1.27 1.27)
					(thickness 0.15)
				)
				(justify left bottom)
				(hide yes)
			)
		)
		(property "Description" "SMD Chip Resistor, 47 kohm, ± 1%, 62.5 mW, 0402 [1005 Metric], Thick Film, General Purpose"
			(at 182.88 199.39 0)
			(effects
				(font
					(size 1.27 1.27)
				)
				(hide yes)
			)
		)
		(property "MPN" "CR0402-FX-4702GLF"
			(at 203.2 179.07 0)
			(effects
				(font
					(size 1.27 1.27)
					(thickness 0.15)
				)
				(justify left bottom)
				(hide yes)
			)
		)
		(property "Manufacturer" "Bourns"
			(at 205.74 179.07 0)
			(effects
				(font
					(size 1.27 1.27)
					(thickness 0.15)
				)
				(justify left bottom)
				(hide yes)
			)
		)
		(property "License" "Apache-2.0"
			(at 208.28 179.07 0)
			(effects
				(font
					(size 1.27 1.27)
					(thickness 0.15)
				)
				(justify left bottom)
				(hide yes)
			)
		)
		(property "Author" "Antmicro"
			(at 210.82 179.07 0)
			(effects
				(font
					(size 1.27 1.27)
					(thickness 0.15)
				)
				(justify left bottom)
				(hide yes)
			)
		)
		(property "Val" "47k"
			(at 181.61 198.12 90)
			(effects
				(font
					(size 1.27 1.27)
					(thickness 0.15)
				)
				(justify left)
			)
		)
		(property "Tolerance" "1%"
			(at 193.04 179.07 0)
			(effects
				(font
					(size 1.27 1.27)
				)
				(justify left bottom)
				(hide yes)
			)
		)
		(pin "1"
		)
		(pin "2"
		)
		(instances
			(project "jetson-agx-thor-baseboard"
				(path ""
					(reference "R288")
					(unit 1)
				)
			)
		)
	)
	(symbol
		(lib_id "antmicropower:GND")
		(at 290.83 237.49 0)
		(mirror y)
		(unit 1)
		(exclude_from_sim no)
		(in_bom yes)
		(on_board yes)
		(dnp no)
		(property "Reference" "#PWR0575"
			(at 281.94 240.03 0)
			(effects
				(font
					(size 1.27 1.27)
					(thickness 0.15)
				)
				(justify left bottom)
				(hide yes)
			)
		)
		(property "Value" "GND"
			(at 290.83 241.3 0)
			(effects
				(font
					(size 1.27 1.27)
					(thickness 0.15)
				)
			)
		)
		(property "Footprint" ""
			(at 281.94 245.11 0)
			(effects
				(font
					(size 1.27 1.27)
					(thickness 0.15)
				)
				(justify left bottom)
				(hide yes)
			)
		)
		(property "Datasheet" ""
			(at 281.94 250.19 0)
			(effects
				(font
					(size 1.27 1.27)
					(thickness 0.15)
				)
				(justify left bottom)
				(hide yes)
			)
		)
		(property "Description" ""
			(at 290.83 237.49 0)
			(effects
				(font
					(size 1.27 1.27)
				)
				(hide yes)
			)
		)
		(property "Author" "Antmicro"
			(at 281.94 245.11 0)
			(effects
				(font
					(size 1.27 1.27)
					(thickness 0.15)
				)
				(justify left bottom)
				(hide yes)
			)
		)
		(property "License" "Apache-2.0"
			(at 281.94 247.65 0)
			(effects
				(font
					(size 1.27 1.27)
					(thickness 0.15)
				)
				(justify left bottom)
				(hide yes)
			)
		)
		(pin "1"
		)
		(instances
			(project "jetson-agx-thor-baseboard"
				(path ""
					(reference "#PWR0575")
					(unit 1)
				)
			)
		)
	)
	(symbol
		(lib_id "antmicroTestPoints:TP_0.75mm_SMD")
		(at 194.31 109.22 0)
		(mirror y)
		(unit 1)
		(exclude_from_sim no)
		(in_bom no)
		(on_board yes)
		(dnp no)
		(fields_autoplaced yes)
		(property "Reference" "TP33"
			(at 189.23 109.22 0)
			(effects
				(font
					(size 1.27 1.27)
					(thickness 0.15)
				)
				(justify left)
			)
		)
		(property "Value" "TP_0.75mm_SMD"
			(at 184.15 113.03 0)
			(effects
				(font
					(size 1.27 1.27)
					(thickness 0.15)
				)
				(justify left bottom)
				(hide yes)
			)
		)
		(property "Footprint" "antmicro-footprints:TP_SMD_0.75mm"
			(at 184.15 115.57 0)
			(effects
				(font
					(size 1.27 1.27)
					(thickness 0.15)
				)
				(justify left bottom)
				(hide yes)
			)
		)
		(property "Datasheet" ""
			(at 176.53 121.92 0)
			(effects
				(font
					(size 1.27 1.27)
					(thickness 0.15)
				)
				(justify left bottom)
				(hide yes)
			)
		)
		(property "Description" "SMT test point"
			(at 194.31 109.22 0)
			(effects
				(font
					(size 1.27 1.27)
				)
				(hide yes)
			)
		)
		(property "MPN" ""
			(at 183.515 120.65 0)
			(effects
				(font
					(size 1.27 1.27)
					(thickness 0.15)
				)
				(justify left bottom)
				(hide yes)
			)
		)
		(property "Manufacturer" ""
			(at 183.515 115.57 0)
			(effects
				(font
					(size 1.27 1.27)
					(thickness 0.15)
				)
				(justify left bottom)
				(hide yes)
			)
		)
		(property "Author" "Antmicro"
			(at 184.15 118.11 0)
			(effects
				(font
					(size 1.27 1.27)
					(thickness 0.15)
				)
				(justify left bottom)
				(hide yes)
			)
		)
		(property "License" "Apache-2.0"
			(at 184.15 120.65 0)
			(effects
				(font
					(size 1.27 1.27)
					(thickness 0.15)
				)
				(justify left bottom)
				(hide yes)
			)
		)
		(pin "1"
		)
		(instances
			(project "jetson-agx-thor-baseboard"
				(path ""
					(reference "TP33")
					(unit 1)
				)
			)
		)
	)
	(symbol
		(lib_id "antmicroTVSDiodes:TPD1E0B04_XDFN-2")
		(at 109.22 209.55 90)
		(unit 1)
		(exclude_from_sim no)
		(in_bom yes)
		(on_board yes)
		(dnp no)
		(property "Reference" "D54"
			(at 111.125 205.74 90)
			(effects
				(font
					(size 1.27 1.27)
				)
				(justify right)
			)
		)
		(property "Value" "TPD1E0B04_XDFN-2"
			(at 119.38 194.31 0)
			(effects
				(font
					(size 1.27 1.27)
					(thickness 0.15)
				)
				(justify left bottom)
				(hide yes)
			)
		)
		(property "Footprint" "antmicro-footprints:XDFN-2_1x0.60mm"
			(at 114.3 194.31 0)
			(effects
				(font
					(size 1.27 1.27)
					(thickness 0.15)
				)
				(justify left bottom)
				(hide yes)
			)
		)
		(property "Datasheet" "https://www.ti.com/general/docs/suppproductinfo.tsp?distId=26&gotoUrl=https://www.ti.com/lit/gpn/tpd1e0b04"
			(at 116.84 194.31 0)
			(effects
				(font
					(size 1.27 1.27)
					(thickness 0.15)
				)
				(justify left bottom)
				(hide yes)
			)
		)
		(property "Description" "Bidirectional TVS, 8 kV,  XDFN-2, 3.6 V, 0.18 pF"
			(at 109.22 209.55 0)
			(effects
				(font
					(size 1.27 1.27)
				)
				(hide yes)
			)
		)
		(property "Manufacturer" "Texas Instruments"
			(at 121.92 194.31 0)
			(effects
				(font
					(size 1.27 1.27)
					(thickness 0.15)
				)
				(justify left bottom)
				(hide yes)
			)
		)
		(property "MPN" "TPD1E0B04DPYR"
			(at 111.125 208.28 90)
			(effects
				(font
					(size 1.27 1.27)
					(thickness 0.15)
				)
				(justify right)
			)
		)
		(property "Author" "Antmicro"
			(at 124.46 194.31 0)
			(effects
				(font
					(size 1.27 1.27)
					(thickness 0.15)
				)
				(justify left bottom)
				(hide yes)
			)
		)
		(property "License" "Apache-2.0"
			(at 127 194.31 0)
			(effects
				(font
					(size 1.27 1.27)
					(thickness 0.15)
				)
				(justify left bottom)
				(hide yes)
			)
		)
		(pin "1"
		)
		(pin "2"
		)
		(instances
			(project "jetson-agx-thor-baseboard"
				(path ""
					(reference "D54")
					(unit 1)
				)
			)
		)
	)
	(symbol
		(lib_id "antmicroResistors0402:R_124k_0402")
		(at 161.29 245.11 90)
		(unit 1)
		(exclude_from_sim no)
		(in_bom yes)
		(on_board yes)
		(dnp no)
		(fields_autoplaced yes)
		(property "Reference" "R408"
			(at 158.75 241.3 90)
			(effects
				(font
					(size 1.27 1.27)
					(thickness 0.15)
				)
				(justify left)
			)
		)
		(property "Value" "R_124k_0402"
			(at 173.99 224.79 0)
			(effects
				(font
					(size 1.27 1.27)
					(thickness 0.15)
				)
				(justify left bottom)
				(hide yes)
			)
		)
		(property "Footprint" "antmicro-footprints:R_0402_1005Metric"
			(at 176.53 224.79 0)
			(effects
				(font
					(size 1.27 1.27)
					(thickness 0.15)
				)
				(justify left bottom)
				(hide yes)
			)
		)
		(property "Datasheet" "https://www.bourns.com/docs/product-datasheets/cr.pdf"
			(at 179.07 224.79 0)
			(effects
				(font
					(size 1.27 1.27)
					(thickness 0.15)
				)
				(justify left bottom)
				(hide yes)
			)
		)
		(property "Description" "SMD Chip Resistor, 124 kohm, ± 1%, 100 mW, 0402 [1005 Metric], Thick Film, Precision"
			(at 191.77 224.79 0)
			(effects
				(font
					(size 1.27 1.27)
				)
				(justify left bottom)
				(hide yes)
			)
		)
		(property "MPN" "CR0402-FX-1243GLF"
			(at 181.61 224.79 0)
			(effects
				(font
					(size 1.27 1.27)
					(thickness 0.15)
				)
				(justify left bottom)
				(hide yes)
			)
		)
		(property "Manufacturer" "Bourns"
			(at 184.15 224.79 0)
			(effects
				(font
					(size 1.27 1.27)
					(thickness 0.15)
				)
				(justify left bottom)
				(hide yes)
			)
		)
		(property "License" "Apache-2.0"
			(at 186.69 224.79 0)
			(effects
				(font
					(size 1.27 1.27)
					(thickness 0.15)
				)
				(justify left bottom)
				(hide yes)
			)
		)
		(property "Author" "Antmicro"
			(at 189.23 224.79 0)
			(effects
				(font
					(size 1.27 1.27)
					(thickness 0.15)
				)
				(justify left bottom)
				(hide yes)
			)
		)
		(property "Val" "124k"
			(at 158.75 243.84 90)
			(effects
				(font
					(size 1.27 1.27)
					(thickness 0.15)
				)
				(justify left)
			)
		)
		(property "Tolerance" "1%"
			(at 171.45 224.79 0)
			(effects
				(font
					(size 1.27 1.27)
				)
				(justify left bottom)
				(hide yes)
			)
		)
		(pin "1"
		)
		(pin "2"
		)
		(instances
			(project ""
				(path ""
					(reference "R408")
					(unit 1)
				)
			)
		)
	)
	(symbol
		(lib_id "antmicroTestPoints:TP_0.75mm_SMD")
		(at 251.46 102.87 0)
		(unit 1)
		(exclude_from_sim no)
		(in_bom no)
		(on_board yes)
		(dnp no)
		(fields_autoplaced yes)
		(property "Reference" "TP8"
			(at 256.54 102.87 0)
			(effects
				(font
					(size 1.27 1.27)
					(thickness 0.15)
				)
				(justify left)
			)
		)
		(property "Value" "TP_0.75mm_SMD"
			(at 261.62 106.68 0)
			(effects
				(font
					(size 1.27 1.27)
					(thickness 0.15)
				)
				(justify left bottom)
				(hide yes)
			)
		)
		(property "Footprint" "antmicro-footprints:TP_SMD_0.75mm"
			(at 261.62 109.22 0)
			(effects
				(font
					(size 1.27 1.27)
					(thickness 0.15)
				)
				(justify left bottom)
				(hide yes)
			)
		)
		(property "Datasheet" ""
			(at 269.24 115.57 0)
			(effects
				(font
					(size 1.27 1.27)
					(thickness 0.15)
				)
				(justify left bottom)
				(hide yes)
			)
		)
		(property "Description" "SMT test point"
			(at 251.46 102.87 0)
			(effects
				(font
					(size 1.27 1.27)
				)
				(hide yes)
			)
		)
		(property "MPN" ""
			(at 262.255 114.3 0)
			(effects
				(font
					(size 1.27 1.27)
					(thickness 0.15)
				)
				(justify left bottom)
				(hide yes)
			)
		)
		(property "Manufacturer" ""
			(at 262.255 109.22 0)
			(effects
				(font
					(size 1.27 1.27)
					(thickness 0.15)
				)
				(justify left bottom)
				(hide yes)
			)
		)
		(property "Author" "Antmicro"
			(at 261.62 111.76 0)
			(effects
				(font
					(size 1.27 1.27)
					(thickness 0.15)
				)
				(justify left bottom)
				(hide yes)
			)
		)
		(property "License" "Apache-2.0"
			(at 261.62 114.3 0)
			(effects
				(font
					(size 1.27 1.27)
					(thickness 0.15)
				)
				(justify left bottom)
				(hide yes)
			)
		)
		(pin "1"
		)
		(instances
			(project "jetson-agx-thor-baseboard"
				(path ""
					(reference "TP8")
					(unit 1)
				)
			)
		)
	)
	(symbol
		(lib_id "antmicroResistors0402:R_10k_0402")
		(at 58.42 256.54 270)
		(mirror x)
		(unit 1)
		(exclude_from_sim no)
		(in_bom yes)
		(on_board yes)
		(dnp no)
		(property "Reference" "R307"
			(at 57.15 252.73 90)
			(effects
				(font
					(size 1.27 1.27)
					(thickness 0.15)
				)
				(justify right)
			)
		)
		(property "Value" "R_10k_0402"
			(at 45.72 236.22 0)
			(effects
				(font
					(size 1.27 1.27)
					(thickness 0.15)
				)
				(justify left bottom)
				(hide yes)
			)
		)
		(property "Footprint" "antmicro-footprints:R_0402_1005Metric"
			(at 43.18 236.22 0)
			(effects
				(font
					(size 1.27 1.27)
					(thickness 0.15)
				)
				(justify left bottom)
				(hide yes)
			)
		)
		(property "Datasheet" "https://www.bourns.com/docs/product-datasheets/cr.pdf"
			(at 40.64 236.22 0)
			(effects
				(font
					(size 1.27 1.27)
					(thickness 0.15)
				)
				(justify left bottom)
				(hide yes)
			)
		)
		(property "Description" "SMD Chip Resistor, 10 kohm, ± 1%, 62.5 mW, 0402 [1005 Metric], Thick Film, General Purpose"
			(at 58.42 256.54 0)
			(effects
				(font
					(size 1.27 1.27)
				)
				(hide yes)
			)
		)
		(property "MPN" "CR0402-FX-1002GLF"
			(at 38.1 236.22 0)
			(effects
				(font
					(size 1.27 1.27)
					(thickness 0.15)
				)
				(justify left bottom)
				(hide yes)
			)
		)
		(property "Manufacturer" "Bourns"
			(at 35.56 236.22 0)
			(effects
				(font
					(size 1.27 1.27)
					(thickness 0.15)
				)
				(justify left bottom)
				(hide yes)
			)
		)
		(property "License" "Apache-2.0"
			(at 33.02 236.22 0)
			(effects
				(font
					(size 1.27 1.27)
					(thickness 0.15)
				)
				(justify left bottom)
				(hide yes)
			)
		)
		(property "Author" "Antmicro"
			(at 30.48 236.22 0)
			(effects
				(font
					(size 1.27 1.27)
					(thickness 0.15)
				)
				(justify left bottom)
				(hide yes)
			)
		)
		(property "Val" "10k"
			(at 57.15 255.27 90)
			(effects
				(font
					(size 1.27 1.27)
					(thickness 0.15)
				)
				(justify right)
			)
		)
		(property "Tolerance" "1%"
			(at 48.26 236.22 0)
			(effects
				(font
					(size 1.27 1.27)
				)
				(justify left bottom)
				(hide yes)
			)
		)
		(pin "2"
		)
		(pin "1"
		)
		(instances
			(project "jetson-agx-thor-baseboard"
				(path ""
					(reference "R307")
					(unit 1)
				)
			)
		)
	)
	(symbol
		(lib_id "antmicropower:GND")
		(at 201.93 154.94 0)
		(unit 1)
		(exclude_from_sim no)
		(in_bom yes)
		(on_board yes)
		(dnp no)
		(property "Reference" "#PWR0492"
			(at 201.93 161.29 0)
			(effects
				(font
					(size 1.27 1.27)
				)
				(justify left bottom)
				(hide yes)
			)
		)
		(property "Value" "GND"
			(at 201.93 158.75 0)
			(effects
				(font
					(size 1.27 1.27)
					(thickness 0.15)
				)
			)
		)
		(property "Footprint" ""
			(at 210.82 162.56 0)
			(effects
				(font
					(size 1.27 1.27)
					(thickness 0.15)
				)
				(justify left bottom)
				(hide yes)
			)
		)
		(property "Datasheet" ""
			(at 210.82 167.64 0)
			(effects
				(font
					(size 1.27 1.27)
					(thickness 0.15)
				)
				(justify left bottom)
				(hide yes)
			)
		)
		(property "Description" ""
			(at 201.93 154.94 0)
			(effects
				(font
					(size 1.27 1.27)
				)
				(hide yes)
			)
		)
		(property "Author" "Antmicro"
			(at 210.82 162.56 0)
			(effects
				(font
					(size 1.27 1.27)
					(thickness 0.15)
				)
				(justify left bottom)
				(hide yes)
			)
		)
		(property "License" "Apache-2.0"
			(at 210.82 165.1 0)
			(effects
				(font
					(size 1.27 1.27)
					(thickness 0.15)
				)
				(justify left bottom)
				(hide yes)
			)
		)
		(pin "1"
		)
		(instances
			(project "jetson-agx-thor-baseboard"
				(path ""
					(reference "#PWR0492")
					(unit 1)
				)
			)
		)
	)
	(symbol
		(lib_id "antmicropower:GND")
		(at 391.16 228.6 0)
		(unit 1)
		(exclude_from_sim no)
		(in_bom yes)
		(on_board yes)
		(dnp no)
		(property "Reference" "#PWR0668"
			(at 391.16 234.95 0)
			(effects
				(font
					(size 1.27 1.27)
				)
				(justify left bottom)
				(hide yes)
			)
		)
		(property "Value" "GND"
			(at 391.16 232.41 0)
			(effects
				(font
					(size 1.27 1.27)
					(thickness 0.15)
				)
			)
		)
		(property "Footprint" ""
			(at 400.05 236.22 0)
			(effects
				(font
					(size 1.27 1.27)
					(thickness 0.15)
				)
				(justify left bottom)
				(hide yes)
			)
		)
		(property "Datasheet" ""
			(at 400.05 241.3 0)
			(effects
				(font
					(size 1.27 1.27)
					(thickness 0.15)
				)
				(justify left bottom)
				(hide yes)
			)
		)
		(property "Description" ""
			(at 391.16 228.6 0)
			(effects
				(font
					(size 1.27 1.27)
				)
				(hide yes)
			)
		)
		(property "Author" "Antmicro"
			(at 400.05 236.22 0)
			(effects
				(font
					(size 1.27 1.27)
					(thickness 0.15)
				)
				(justify left bottom)
				(hide yes)
			)
		)
		(property "License" "Apache-2.0"
			(at 400.05 238.76 0)
			(effects
				(font
					(size 1.27 1.27)
					(thickness 0.15)
				)
				(justify left bottom)
				(hide yes)
			)
		)
		(pin "1"
		)
		(instances
			(project "jetson-agx-thor-baseboard"
				(path ""
					(reference "#PWR0668")
					(unit 1)
				)
			)
		)
	)
	(symbol
		(lib_id "antmicroCapacitors0402:C_1u_25V_0402")
		(at 91.44 181.61 270)
		(mirror x)
		(unit 1)
		(exclude_from_sim no)
		(in_bom yes)
		(on_board yes)
		(dnp no)
		(property "Reference" "C404"
			(at 88.9 177.7936 90)
			(effects
				(font
					(size 1.27 1.27)
					(thickness 0.15)
				)
				(justify right)
			)
		)
		(property "Value" "C_1u_25V_0402"
			(at 81.28 161.29 0)
			(effects
				(font
					(size 1.27 1.27)
					(thickness 0.15)
				)
				(justify left bottom)
				(hide yes)
			)
		)
		(property "Footprint" "antmicro-footprints:C_0402_1005Metric"
			(at 78.74 161.29 0)
			(effects
				(font
					(size 1.27 1.27)
					(thickness 0.15)
				)
				(justify left bottom)
				(hide yes)
			)
		)
		(property "Datasheet" "https://www.murata.com/products/productdetail?partno=GRM155R61E105KE11%23"
			(at 76.2 161.29 0)
			(effects
				(font
					(size 1.27 1.27)
					(thickness 0.15)
				)
				(justify left bottom)
				(hide yes)
			)
		)
		(property "Description" "SMD Multilayer Ceramic Capacitor, 1 µF, 25 V, 0402 [1005 Metric], ± 10%, X5R, GRM Series"
			(at 91.44 181.61 0)
			(effects
				(font
					(size 1.27 1.27)
				)
				(hide yes)
			)
		)
		(property "MPN" "GRM155R61E105KE11J"
			(at 73.66 161.29 0)
			(effects
				(font
					(size 1.27 1.27)
					(thickness 0.15)
				)
				(justify left bottom)
				(hide yes)
			)
		)
		(property "Manufacturer" "Murata"
			(at 71.12 161.29 0)
			(effects
				(font
					(size 1.27 1.27)
					(thickness 0.15)
				)
				(justify left bottom)
				(hide yes)
			)
		)
		(property "License" "Apache-2.0"
			(at 68.58 161.29 0)
			(effects
				(font
					(size 1.27 1.27)
					(thickness 0.15)
				)
				(justify left bottom)
				(hide yes)
			)
		)
		(property "Author" "Antmicro"
			(at 66.04 161.29 0)
			(effects
				(font
					(size 1.27 1.27)
					(thickness 0.15)
				)
				(justify left bottom)
				(hide yes)
			)
		)
		(property "Val" "1u"
			(at 88.9 180.3336 90)
			(effects
				(font
					(size 1.27 1.27)
					(thickness 0.15)
				)
				(justify right)
			)
		)
		(property "Voltage" "25V"
			(at 63.5 161.29 0)
			(effects
				(font
					(size 1.27 1.27)
				)
				(justify left bottom)
				(hide yes)
			)
		)
		(property "Dielectric" "X5R"
			(at 60.96 161.29 0)
			(effects
				(font
					(size 1.27 1.27)
				)
				(justify left bottom)
				(hide yes)
			)
		)
		(pin "2"
		)
		(pin "1"
		)
		(instances
			(project "jetson-agx-thor-baseboard"
				(path ""
					(reference "C404")
					(unit 1)
				)
			)
		)
	)
	(symbol
		(lib_id "antmicropower:GND")
		(at 96.52 160.02 0)
		(unit 1)
		(exclude_from_sim no)
		(in_bom yes)
		(on_board yes)
		(dnp no)
		(property "Reference" "#PWR0512"
			(at 105.41 162.56 0)
			(effects
				(font
					(size 1.27 1.27)
					(thickness 0.15)
				)
				(justify left bottom)
				(hide yes)
			)
		)
		(property "Value" "GND"
			(at 96.52 163.83 0)
			(effects
				(font
					(size 1.27 1.27)
					(thickness 0.15)
				)
			)
		)
		(property "Footprint" ""
			(at 105.41 167.64 0)
			(effects
				(font
					(size 1.27 1.27)
					(thickness 0.15)
				)
				(justify left bottom)
				(hide yes)
			)
		)
		(property "Datasheet" ""
			(at 105.41 172.72 0)
			(effects
				(font
					(size 1.27 1.27)
					(thickness 0.15)
				)
				(justify left bottom)
				(hide yes)
			)
		)
		(property "Description" ""
			(at 96.52 160.02 0)
			(effects
				(font
					(size 1.27 1.27)
				)
				(hide yes)
			)
		)
		(property "Author" "Antmicro"
			(at 105.41 167.64 0)
			(effects
				(font
					(size 1.27 1.27)
					(thickness 0.15)
				)
				(justify left bottom)
				(hide yes)
			)
		)
		(property "License" "Apache-2.0"
			(at 105.41 170.18 0)
			(effects
				(font
					(size 1.27 1.27)
					(thickness 0.15)
				)
				(justify left bottom)
				(hide yes)
			)
		)
		(pin "1"
		)
		(instances
			(project "jetson-agx-thor-baseboard"
				(path ""
					(reference "#PWR0512")
					(unit 1)
				)
			)
		)
	)
	(symbol
		(lib_id "antmicroCapacitors0402:C_10u_0402")
		(at 133.35 48.26 90)
		(unit 1)
		(exclude_from_sim no)
		(in_bom yes)
		(on_board yes)
		(dnp no)
		(fields_autoplaced yes)
		(property "Reference" "C16"
			(at 135.89 44.4436 90)
			(effects
				(font
					(size 1.27 1.27)
					(thickness 0.15)
				)
				(justify right)
			)
		)
		(property "Value" "C_10u_0402"
			(at 143.51 27.94 0)
			(effects
				(font
					(size 1.27 1.27)
					(thickness 0.15)
				)
				(justify left bottom)
				(hide yes)
			)
		)
		(property "Footprint" "antmicro-footprints:C_0402_1005Metric"
			(at 146.05 27.94 0)
			(effects
				(font
					(size 1.27 1.27)
					(thickness 0.15)
				)
				(justify left bottom)
				(hide yes)
			)
		)
		(property "Datasheet" "https://www.yageo.com/en/Chart/Download/pdf/CC0402MRX5R5BB106"
			(at 148.59 27.94 0)
			(effects
				(font
					(size 1.27 1.27)
					(thickness 0.15)
				)
				(justify left bottom)
				(hide yes)
			)
		)
		(property "Description" "SMD Multilayer Ceramic Capacitor, 10 µF, 6.3 V, 0402 [1005 Metric], ± 20%, X5R, CC Series"
			(at 133.35 48.26 0)
			(effects
				(font
					(size 1.27 1.27)
				)
				(hide yes)
			)
		)
		(property "MPN" "CC0402MRX5R5BB106"
			(at 151.13 27.94 0)
			(effects
				(font
					(size 1.27 1.27)
					(thickness 0.15)
				)
				(justify left bottom)
				(hide yes)
			)
		)
		(property "Manufacturer" "YAGEO"
			(at 153.67 27.94 0)
			(effects
				(font
					(size 1.27 1.27)
					(thickness 0.15)
				)
				(justify left bottom)
				(hide yes)
			)
		)
		(property "License" "Apache-2.0"
			(at 156.21 27.94 0)
			(effects
				(font
					(size 1.27 1.27)
					(thickness 0.15)
				)
				(justify left bottom)
				(hide yes)
			)
		)
		(property "Author" "Antmicro"
			(at 158.75 27.94 0)
			(effects
				(font
					(size 1.27 1.27)
					(thickness 0.15)
				)
				(justify left bottom)
				(hide yes)
			)
		)
		(property "Val" "10u"
			(at 135.89 46.9836 90)
			(effects
				(font
					(size 1.27 1.27)
					(thickness 0.15)
				)
				(justify right)
			)
		)
		(property "Voltage" ""
			(at 161.29 27.94 0)
			(effects
				(font
					(size 1.27 1.27)
				)
				(justify left bottom)
				(hide yes)
			)
		)
		(property "Dielectric" "template_dielectric"
			(at 163.83 27.94 0)
			(effects
				(font
					(size 1.27 1.27)
				)
				(justify left bottom)
				(hide yes)
			)
		)
		(pin "1"
		)
		(pin "2"
		)
		(instances
			(project "jetson-agx-thor-baseboard"
				(path ""
					(reference "C16")
					(unit 1)
				)
			)
		)
	)
	(symbol
		(lib_id "antmicroResistors0402:R_2k2_0402")
		(at 148.59 78.74 90)
		(unit 1)
		(exclude_from_sim no)
		(in_bom yes)
		(on_board yes)
		(dnp no)
		(property "Reference" "R6"
			(at 149.86 74.93 90)
			(effects
				(font
					(size 1.27 1.27)
				)
				(justify right)
			)
		)
		(property "Value" "R_2k2_0402"
			(at 161.29 58.42 0)
			(effects
				(font
					(size 1.27 1.27)
					(thickness 0.15)
				)
				(justify left bottom)
				(hide yes)
			)
		)
		(property "Footprint" "antmicro-footprints:R_0402_1005Metric"
			(at 163.83 58.42 0)
			(effects
				(font
					(size 1.27 1.27)
					(thickness 0.15)
				)
				(justify left bottom)
				(hide yes)
			)
		)
		(property "Datasheet" "https://www.bourns.com/docs/product-datasheets/cr.pdf"
			(at 166.37 58.42 0)
			(effects
				(font
					(size 1.27 1.27)
					(thickness 0.15)
				)
				(justify left bottom)
				(hide yes)
			)
		)
		(property "Description" "SMD Chip Resistor, 2.2 kohm, ± 1%, 62.5 mW, 0402 [1005 Metric], Thick Film, General Purpose"
			(at 148.59 78.74 0)
			(effects
				(font
					(size 1.27 1.27)
				)
				(hide yes)
			)
		)
		(property "Manufacturer" "Bourns"
			(at 171.45 58.42 0)
			(effects
				(font
					(size 1.27 1.27)
					(thickness 0.15)
				)
				(justify left bottom)
				(hide yes)
			)
		)
		(property "MPN" "CR0402-FX-2201GLF"
			(at 168.91 58.42 0)
			(effects
				(font
					(size 1.27 1.27)
					(thickness 0.15)
				)
				(justify left bottom)
				(hide yes)
			)
		)
		(property "Val" "2k2"
			(at 149.86 77.47 90)
			(effects
				(font
					(size 1.27 1.27)
					(thickness 0.15)
				)
				(justify right)
			)
		)
		(property "License" "Apache-2.0"
			(at 173.99 58.42 0)
			(effects
				(font
					(size 1.27 1.27)
					(thickness 0.15)
				)
				(justify left bottom)
				(hide yes)
			)
		)
		(property "Author" "Antmicro"
			(at 176.53 58.42 0)
			(effects
				(font
					(size 1.27 1.27)
					(thickness 0.15)
				)
				(justify left bottom)
				(hide yes)
			)
		)
		(property "Tolerance" "1%"
			(at 158.75 58.42 0)
			(effects
				(font
					(size 1.27 1.27)
				)
				(justify left bottom)
				(hide yes)
			)
		)
		(pin "1"
		)
		(pin "2"
		)
		(instances
			(project "jetson-agx-thor-baseboard"
				(path ""
					(reference "R6")
					(unit 1)
				)
			)
		)
	)
	(symbol
		(lib_id "antmicroTestPoints:TP_0.75mm_SMD")
		(at 251.46 115.57 0)
		(unit 1)
		(exclude_from_sim no)
		(in_bom no)
		(on_board yes)
		(dnp no)
		(fields_autoplaced yes)
		(property "Reference" "TP59"
			(at 256.54 115.57 0)
			(effects
				(font
					(size 1.27 1.27)
					(thickness 0.15)
				)
				(justify left)
			)
		)
		(property "Value" "TP_0.75mm_SMD"
			(at 261.62 119.38 0)
			(effects
				(font
					(size 1.27 1.27)
					(thickness 0.15)
				)
				(justify left bottom)
				(hide yes)
			)
		)
		(property "Footprint" "antmicro-footprints:TP_SMD_0.75mm"
			(at 261.62 121.92 0)
			(effects
				(font
					(size 1.27 1.27)
					(thickness 0.15)
				)
				(justify left bottom)
				(hide yes)
			)
		)
		(property "Datasheet" ""
			(at 269.24 128.27 0)
			(effects
				(font
					(size 1.27 1.27)
					(thickness 0.15)
				)
				(justify left bottom)
				(hide yes)
			)
		)
		(property "Description" "SMT test point"
			(at 251.46 115.57 0)
			(effects
				(font
					(size 1.27 1.27)
				)
				(hide yes)
			)
		)
		(property "MPN" ""
			(at 262.255 127 0)
			(effects
				(font
					(size 1.27 1.27)
					(thickness 0.15)
				)
				(justify left bottom)
				(hide yes)
			)
		)
		(property "Manufacturer" ""
			(at 262.255 121.92 0)
			(effects
				(font
					(size 1.27 1.27)
					(thickness 0.15)
				)
				(justify left bottom)
				(hide yes)
			)
		)
		(property "Author" "Antmicro"
			(at 261.62 124.46 0)
			(effects
				(font
					(size 1.27 1.27)
					(thickness 0.15)
				)
				(justify left bottom)
				(hide yes)
			)
		)
		(property "License" "Apache-2.0"
			(at 261.62 127 0)
			(effects
				(font
					(size 1.27 1.27)
					(thickness 0.15)
				)
				(justify left bottom)
				(hide yes)
			)
		)
		(pin "1"
		)
		(instances
			(project "jetson-agx-thor-baseboard"
				(path ""
					(reference "TP59")
					(unit 1)
				)
			)
		)
	)
	(symbol
		(lib_id "antmicropower:+3V3_AON")
		(at 60.96 165.1 0)
		(unit 1)
		(exclude_from_sim no)
		(in_bom yes)
		(on_board yes)
		(dnp no)
		(fields_autoplaced yes)
		(property "Reference" "#PWR0552"
			(at 60.96 168.91 0)
			(effects
				(font
					(size 1.27 1.27)
				)
				(hide yes)
			)
		)
		(property "Value" "+3V3_AON"
			(at 60.96 160.02 0)
			(effects
				(font
					(size 1.27 1.27)
				)
			)
		)
		(property "Footprint" ""
			(at 60.96 165.1 0)
			(effects
				(font
					(size 1.27 1.27)
				)
				(hide yes)
			)
		)
		(property "Datasheet" ""
			(at 60.96 165.1 0)
			(effects
				(font
					(size 1.27 1.27)
				)
				(hide yes)
			)
		)
		(property "Description" ""
			(at 60.96 165.1 0)
			(effects
				(font
					(size 1.27 1.27)
				)
				(hide yes)
			)
		)
		(pin "1"
		)
		(instances
			(project "jetson-agx-thor-baseboard"
				(path ""
					(reference "#PWR0552")
					(unit 1)
				)
			)
		)
	)
	(symbol
		(lib_id "antmicroTestPoints:TP_0.75mm_SMD")
		(at 240.03 241.3 0)
		(unit 1)
		(exclude_from_sim no)
		(in_bom no)
		(on_board yes)
		(dnp no)
		(fields_autoplaced yes)
		(property "Reference" "TP122"
			(at 245.11 241.3 0)
			(effects
				(font
					(size 1.27 1.27)
					(thickness 0.15)
				)
				(justify left)
			)
		)
		(property "Value" "TP_0.75mm_SMD"
			(at 250.19 245.11 0)
			(effects
				(font
					(size 1.27 1.27)
					(thickness 0.15)
				)
				(justify left bottom)
				(hide yes)
			)
		)
		(property "Footprint" "antmicro-footprints:TP_SMD_0.75mm"
			(at 250.19 247.65 0)
			(effects
				(font
					(size 1.27 1.27)
					(thickness 0.15)
				)
				(justify left bottom)
				(hide yes)
			)
		)
		(property "Datasheet" ""
			(at 257.81 254 0)
			(effects
				(font
					(size 1.27 1.27)
					(thickness 0.15)
				)
				(justify left bottom)
				(hide yes)
			)
		)
		(property "Description" "SMT test point"
			(at 240.03 241.3 0)
			(effects
				(font
					(size 1.27 1.27)
				)
				(hide yes)
			)
		)
		(property "MPN" ""
			(at 250.825 252.73 0)
			(effects
				(font
					(size 1.27 1.27)
					(thickness 0.15)
				)
				(justify left bottom)
				(hide yes)
			)
		)
		(property "Manufacturer" ""
			(at 250.825 247.65 0)
			(effects
				(font
					(size 1.27 1.27)
					(thickness 0.15)
				)
				(justify left bottom)
				(hide yes)
			)
		)
		(property "Author" "Antmicro"
			(at 250.19 250.19 0)
			(effects
				(font
					(size 1.27 1.27)
					(thickness 0.15)
				)
				(justify left bottom)
				(hide yes)
			)
		)
		(property "License" "Apache-2.0"
			(at 250.19 252.73 0)
			(effects
				(font
					(size 1.27 1.27)
					(thickness 0.15)
				)
				(justify left bottom)
				(hide yes)
			)
		)
		(pin "1"
		)
		(instances
			(project "jetson-agx-thor-baseboard"
				(path ""
					(reference "TP122")
					(unit 1)
				)
			)
		)
	)
	(symbol
		(lib_id "antmicroTransistorsFETsMOSFETsSingle:SISS05DN-T1-GE3")
		(at 54.61 38.1 270)
		(mirror x)
		(unit 1)
		(exclude_from_sim no)
		(in_bom yes)
		(on_board yes)
		(dnp no)
		(property "Reference" "Q9"
			(at 57.15 25.4 90)
			(effects
				(font
					(size 1.27 1.27)
					(thickness 0.15)
				)
			)
		)
		(property "Value" "SISS05DN-T1-GE3"
			(at 44.45 22.86 0)
			(effects
				(font
					(size 1.27 1.27)
					(thickness 0.15)
				)
				(justify left bottom)
				(hide yes)
			)
		)
		(property "Footprint" "antmicro-footprints:Vishay_PowerPAK_1212-8_Single"
			(at 41.91 22.86 0)
			(effects
				(font
					(size 1.27 1.27)
					(thickness 0.15)
				)
				(justify left bottom)
				(hide yes)
			)
		)
		(property "Datasheet" "https://www.vishay.com/docs/77029/siss05dn.pdf"
			(at 39.37 22.86 0)
			(effects
				(font
					(size 1.27 1.27)
					(thickness 0.15)
				)
				(justify left bottom)
				(hide yes)
			)
		)
		(property "Description" "Power MOSFET, P Channel, 30 V, 108 A, 0.0035 ohm, PowerPAK 1212, Surface Mount"
			(at 36.83 22.86 0)
			(effects
				(font
					(size 1.27 1.27)
					(thickness 0.15)
				)
				(justify left bottom)
				(hide yes)
			)
		)
		(property "MPN" "SISS05DN-T1-GE3"
			(at 57.15 27.94 90)
			(effects
				(font
					(size 1.27 1.27)
					(thickness 0.15)
				)
			)
		)
		(property "Manufacturer" "Vishay"
			(at 34.29 22.86 0)
			(effects
				(font
					(size 1.27 1.27)
					(thickness 0.15)
				)
				(justify left bottom)
				(hide yes)
			)
		)
		(property "Author" "Antmicro"
			(at 31.75 22.86 0)
			(effects
				(font
					(size 1.27 1.27)
					(thickness 0.15)
				)
				(justify left bottom)
				(hide yes)
			)
		)
		(property "License" "Apache-2.0"
			(at 29.21 22.86 0)
			(effects
				(font
					(size 1.27 1.27)
					(thickness 0.15)
				)
				(justify left bottom)
				(hide yes)
			)
		)
		(pin "1"
		)
		(pin "4"
		)
		(pin "3"
		)
		(pin "5"
		)
		(pin "2"
		)
		(instances
			(project "jetson-agx-thor-baseboard"
				(path ""
					(reference "Q9")
					(unit 1)
				)
			)
		)
	)
	(symbol
		(lib_id "antmicroResistors0402:R_3k92_0402")
		(at 199.39 237.49 90)
		(unit 1)
		(exclude_from_sim no)
		(in_bom yes)
		(on_board yes)
		(dnp no)
		(fields_autoplaced yes)
		(property "Reference" "R45"
			(at 201.93 233.68 90)
			(effects
				(font
					(size 1.27 1.27)
					(thickness 0.15)
				)
				(justify right)
			)
		)
		(property "Value" "R_3k92_0402"
			(at 212.09 217.17 0)
			(effects
				(font
					(size 1.27 1.27)
					(thickness 0.15)
				)
				(justify left bottom)
				(hide yes)
			)
		)
		(property "Footprint" "antmicro-footprints:R_0402_1005Metric"
			(at 214.63 217.17 0)
			(effects
				(font
					(size 1.27 1.27)
					(thickness 0.15)
				)
				(justify left bottom)
				(hide yes)
			)
		)
		(property "Datasheet" "https://www.bourns.com/docs/product-datasheets/cr.pdf"
			(at 217.17 217.17 0)
			(effects
				(font
					(size 1.27 1.27)
					(thickness 0.15)
				)
				(justify left bottom)
				(hide yes)
			)
		)
		(property "Description" "SMD Chip Resistor, 3.92 kohm, ± 1%, 100 mW, 0402 [1005 Metric], Thick Film, Precision"
			(at 229.87 217.17 0)
			(effects
				(font
					(size 1.27 1.27)
				)
				(justify left bottom)
				(hide yes)
			)
		)
		(property "MPN" "CR0402-FX-3921GLF"
			(at 219.71 217.17 0)
			(effects
				(font
					(size 1.27 1.27)
					(thickness 0.15)
				)
				(justify left bottom)
				(hide yes)
			)
		)
		(property "Manufacturer" "Bourns"
			(at 222.25 217.17 0)
			(effects
				(font
					(size 1.27 1.27)
					(thickness 0.15)
				)
				(justify left bottom)
				(hide yes)
			)
		)
		(property "License" "Apache-2.0"
			(at 224.79 217.17 0)
			(effects
				(font
					(size 1.27 1.27)
					(thickness 0.15)
				)
				(justify left bottom)
				(hide yes)
			)
		)
		(property "Author" "Antmicro"
			(at 227.33 217.17 0)
			(effects
				(font
					(size 1.27 1.27)
					(thickness 0.15)
				)
				(justify left bottom)
				(hide yes)
			)
		)
		(property "Val" "3k92"
			(at 201.93 236.22 90)
			(effects
				(font
					(size 1.27 1.27)
					(thickness 0.15)
				)
				(justify right)
			)
		)
		(property "Tolerance" "1%"
			(at 209.55 217.17 0)
			(effects
				(font
					(size 1.27 1.27)
				)
				(justify left bottom)
				(hide yes)
			)
		)
		(pin "1"
		)
		(pin "2"
		)
		(instances
			(project ""
				(path ""
					(reference "R45")
					(unit 1)
				)
			)
		)
	)
	(symbol
		(lib_id "antmicropower:+3V3_AON")
		(at 97.79 167.64 0)
		(unit 1)
		(exclude_from_sim no)
		(in_bom yes)
		(on_board yes)
		(dnp no)
		(property "Reference" "#PWR0767"
			(at 97.79 171.45 0)
			(effects
				(font
					(size 1.27 1.27)
				)
				(hide yes)
			)
		)
		(property "Value" "+3V3_AON"
			(at 103.632 165.608 0)
			(effects
				(font
					(size 1.27 1.27)
				)
			)
		)
		(property "Footprint" ""
			(at 97.79 167.64 0)
			(effects
				(font
					(size 1.27 1.27)
				)
				(hide yes)
			)
		)
		(property "Datasheet" ""
			(at 97.79 167.64 0)
			(effects
				(font
					(size 1.27 1.27)
				)
				(hide yes)
			)
		)
		(property "Description" ""
			(at 97.79 167.64 0)
			(effects
				(font
					(size 1.27 1.27)
				)
				(hide yes)
			)
		)
		(pin "1"
		)
		(instances
			(project "jetson-agx-thor-baseboard"
				(path ""
					(reference "#PWR0767")
					(unit 1)
				)
			)
		)
	)
	(symbol
		(lib_id "antmicroCapacitors0402:C_10u_0402")
		(at 170.18 48.26 90)
		(unit 1)
		(exclude_from_sim no)
		(in_bom yes)
		(on_board yes)
		(dnp no)
		(property "Reference" "C25"
			(at 172.72 44.4436 90)
			(effects
				(font
					(size 1.27 1.27)
					(thickness 0.15)
				)
				(justify right)
			)
		)
		(property "Value" "C_10u_0402"
			(at 180.34 27.94 0)
			(effects
				(font
					(size 1.27 1.27)
					(thickness 0.15)
				)
				(justify left bottom)
				(hide yes)
			)
		)
		(property "Footprint" "antmicro-footprints:C_0402_1005Metric"
			(at 182.88 27.94 0)
			(effects
				(font
					(size 1.27 1.27)
					(thickness 0.15)
				)
				(justify left bottom)
				(hide yes)
			)
		)
		(property "Datasheet" "https://www.yageo.com/en/Chart/Download/pdf/CC0402MRX5R5BB106"
			(at 185.42 27.94 0)
			(effects
				(font
					(size 1.27 1.27)
					(thickness 0.15)
				)
				(justify left bottom)
				(hide yes)
			)
		)
		(property "Description" "SMD Multilayer Ceramic Capacitor, 10 µF, 6.3 V, 0402 [1005 Metric], ± 20%, X5R, CC Series"
			(at 170.18 48.26 0)
			(effects
				(font
					(size 1.27 1.27)
				)
				(hide yes)
			)
		)
		(property "MPN" "CC0402MRX5R5BB106"
			(at 187.96 27.94 0)
			(effects
				(font
					(size 1.27 1.27)
					(thickness 0.15)
				)
				(justify left bottom)
				(hide yes)
			)
		)
		(property "Manufacturer" "YAGEO"
			(at 190.5 27.94 0)
			(effects
				(font
					(size 1.27 1.27)
					(thickness 0.15)
				)
				(justify left bottom)
				(hide yes)
			)
		)
		(property "License" "Apache-2.0"
			(at 193.04 27.94 0)
			(effects
				(font
					(size 1.27 1.27)
					(thickness 0.15)
				)
				(justify left bottom)
				(hide yes)
			)
		)
		(property "Author" "Antmicro"
			(at 195.58 27.94 0)
			(effects
				(font
					(size 1.27 1.27)
					(thickness 0.15)
				)
				(justify left bottom)
				(hide yes)
			)
		)
		(property "Val" "10u"
			(at 172.72 46.9836 90)
			(effects
				(font
					(size 1.27 1.27)
					(thickness 0.15)
				)
				(justify right)
			)
		)
		(property "Voltage" ""
			(at 198.12 27.94 0)
			(effects
				(font
					(size 1.27 1.27)
				)
				(justify left bottom)
				(hide yes)
			)
		)
		(property "Dielectric" "template_dielectric"
			(at 200.66 27.94 0)
			(effects
				(font
					(size 1.27 1.27)
				)
				(justify left bottom)
				(hide yes)
			)
		)
		(pin "1"
		)
		(pin "2"
		)
		(instances
			(project "jetson-agx-thor-baseboard"
				(path ""
					(reference "C25")
					(unit 1)
				)
			)
		)
	)
	(symbol
		(lib_id "antmicroB2BConnectors:Hermaphroditic_Molex_203456-0003_CUSTOM_Jetson_AGX_Thor_H8mm")
		(at 194.31 64.77 0)
		(unit 1)
		(exclude_from_sim no)
		(in_bom yes)
		(on_board yes)
		(dnp no)
		(fields_autoplaced yes)
		(property "Reference" "J1"
			(at 224.155 57.15 0)
			(effects
				(font
					(size 1.27 1.27)
				)
			)
		)
		(property "Value" "Hermaphroditic_Molex_203456-0003_CUSTOM_Jetson_AGX_Thor_H8mm"
			(at 270.764 70.866 0)
			(effects
				(font
					(size 1.27 1.27)
				)
				(justify left bottom)
				(hide yes)
			)
		)
		(property "Footprint" "antmicro-footprints:Conn_Hermaphroditic_Molex_203456-0003_mirrored"
			(at 270.764 73.152 0)
			(effects
				(font
					(size 1.27 1.27)
				)
				(justify left bottom)
				(hide yes)
			)
		)
		(property "Datasheet" "https://www.molex.com/content/dam/molex/molex-dot-com/products/automated/en-us/salesdrawingpdf/203/203456/2034560003_sd.pdf?inline"
			(at 270.764 75.438 0)
			(effects
				(font
					(size 1.27 1.27)
				)
				(justify left bottom)
				(hide yes)
			)
		)
		(property "Description" "Mirror Mezz Hermaphroditic Connector, 5.50mm Connector Height, BGA-Attach Mounting, 7 Pair, 11 Row, 699 Circuits, 0.76µm Gold Plating, without Pegs"
			(at 270.764 84.074 0)
			(effects
				(font
					(size 1.27 1.27)
				)
				(justify left bottom)
				(hide yes)
			)
		)
		(property "MPN" "203456-0003"
			(at 224.155 59.69 0)
			(effects
				(font
					(size 1.27 1.27)
				)
			)
		)
		(property "Manufacturer" "Molex"
			(at 270.764 77.724 0)
			(effects
				(font
					(size 1.27 1.27)
				)
				(justify left bottom)
				(hide yes)
			)
		)
		(property "Author" "Antmicro"
			(at 270.764 79.756 0)
			(effects
				(font
					(size 1.27 1.27)
				)
				(justify left bottom)
				(hide yes)
			)
		)
		(property "License" "Apache-2.0"
			(at 270.764 81.788 0)
			(effects
				(font
					(size 1.27 1.27)
				)
				(justify left bottom)
				(hide yes)
			)
		)
		(pin "J64"
		)
		(pin "L55"
		)
		(pin "L59"
		)
		(pin "B27"
		)
		(pin "E62"
		)
		(pin "D65"
		)
		(pin "A46"
		)
		(pin "B10"
		)
		(pin "H1"
		)
		(pin "B14"
		)
		(pin "B11"
		)
		(pin "G57"
		)
		(pin "B7"
		)
		(pin "J46"
		)
		(pin "J49"
		)
		(pin "E13"
		)
		(pin "B35"
		)
		(pin "A63"
		)
		(pin "A43"
		)
		(pin "D3"
		)
		(pin "D26"
		)
		(pin "E1"
		)
		(pin "B38"
		)
		(pin "B19"
		)
		(pin "B23"
		)
		(pin "B22"
		)
		(pin "H3"
		)
		(pin "G63"
		)
		(pin "C13"
		)
		(pin "L24"
		)
		(pin "L25"
		)
		(pin "C32"
		)
		(pin "D32"
		)
		(pin "J35"
		)
		(pin "J34"
		)
		(pin "B46"
		)
		(pin "A44"
		)
		(pin "A45"
		)
		(pin "C47"
		)
		(pin "E33"
		)
		(pin "E16"
		)
		(pin "B53"
		)
		(pin "H11"
		)
		(pin "H14"
		)
		(pin "L53"
		)
		(pin "F61"
		)
		(pin "L56"
		)
		(pin "F65"
		)
		(pin "J65"
		)
		(pin "D11"
		)
		(pin "G2"
		)
		(pin "L60"
		)
		(pin "G64"
		)
		(pin "A3"
		)
		(pin "D4"
		)
		(pin "D23"
		)
		(pin "D64"
		)
		(pin "E2"
		)
		(pin "C29"
		)
		(pin "D63"
		)
		(pin "C63"
		)
		(pin "E25"
		)
		(pin "B47"
		)
		(pin "E9"
		)
		(pin "K3"
		)
		(pin "F2"
		)
		(pin "F11"
		)
		(pin "G1"
		)
		(pin "E3"
		)
		(pin "J17"
		)
		(pin "J20"
		)
		(pin "L7"
		)
		(pin "L54"
		)
		(pin "B34"
		)
		(pin "J2"
		)
		(pin "A49"
		)
		(pin "G65"
		)
		(pin "C3"
		)
		(pin "L35"
		)
		(pin "D2"
		)
		(pin "K42"
		)
		(pin "K45"
		)
		(pin "E40"
		)
		(pin "E35"
		)
		(pin "G39"
		)
		(pin "G38"
		)
		(pin "H36"
		)
		(pin "H37"
		)
		(pin "F50"
		)
		(pin "D22"
		)
		(pin "E17"
		)
		(pin "J1"
		)
		(pin "G52"
		)
		(pin "C65"
		)
		(pin "F19"
		)
		(pin "B31"
		)
		(pin "B4"
		)
		(pin "C1"
		)
		(pin "K48"
		)
		(pin "K55"
		)
		(pin "C2"
		)
		(pin "B3"
		)
		(pin "K63"
		)
		(pin "K8"
		)
		(pin "B63"
		)
		(pin "D57"
		)
		(pin "A52"
		)
		(pin "G12"
		)
		(pin "H5"
		)
		(pin "K6"
		)
		(pin "J5"
		)
		(pin "J6"
		)
		(pin "J7"
		)
		(pin "A37"
		)
		(pin "C36"
		)
		(pin "G26"
		)
		(pin "J26"
		)
		(pin "C64"
		)
		(pin "J55"
		)
		(pin "A47"
		)
		(pin "A48"
		)
		(pin "A61"
		)
		(pin "L52"
		)
		(pin "C9"
		)
		(pin "A53"
		)
		(pin "C53"
		)
		(pin "K10"
		)
		(pin "K9"
		)
		(pin "E31"
		)
		(pin "E30"
		)
		(pin "D9"
		)
		(pin "C24"
		)
		(pin "C52"
		)
		(pin "G25"
		)
		(pin "F64"
		)
		(pin "F33"
		)
		(pin "E23"
		)
		(pin "E22"
		)
		(pin "E52"
		)
		(pin "F63"
		)
		(pin "G62"
		)
		(pin "G9"
		)
		(pin "J25"
		)
		(pin "J28"
		)
		(pin "F14"
		)
		(pin "D52"
		)
		(pin "B51"
		)
		(pin "B52"
		)
		(pin "B5"
		)
		(pin "K7"
		)
		(pin "H9"
		)
		(pin "L14"
		)
		(pin "C50"
		)
		(pin "H49"
		)
		(pin "H48"
		)
		(pin "J63"
		)
		(pin "B26"
		)
		(pin "D50"
		)
		(pin "A56"
		)
		(pin "D55"
		)
		(pin "D60"
		)
		(pin "E61"
		)
		(pin "D62"
		)
		(pin "B17"
		)
		(pin "K32"
		)
		(pin "G8"
		)
		(pin "C8"
		)
		(pin "L19"
		)
		(pin "C30"
		)
		(pin "A30"
		)
		(pin "L62"
		)
		(pin "L61"
		)
		(pin "D39"
		)
		(pin "D27"
		)
		(pin "E37"
		)
		(pin "G13"
		)
		(pin "E63"
		)
		(pin "B39"
		)
		(pin "D54"
		)
		(pin "J51"
		)
		(pin "K52"
		)
		(pin "K51"
		)
		(pin "E6"
		)
		(pin "B13"
		)
		(pin "D12"
		)
		(pin "F10"
		)
		(pin "F9"
		)
		(pin "C39"
		)
		(pin "A58"
		)
		(pin "B58"
		)
		(pin "F21"
		)
		(pin "F43"
		)
		(pin "F42"
		)
		(pin "E42"
		)
		(pin "J19"
		)
		(pin "D48"
		)
		(pin "A10"
		)
		(pin "A11"
		)
		(pin "K16"
		)
		(pin "F12"
		)
		(pin "F13"
		)
		(pin "G43"
		)
		(pin "K49"
		)
		(pin "H51"
		)
		(pin "J52"
		)
		(pin "K24"
		)
		(pin "G27"
		)
		(pin "K12"
		)
		(pin "H12"
		)
		(pin "D47"
		)
		(pin "D29"
		)
		(pin "B29"
		)
		(pin "F18"
		)
		(pin "F15"
		)
		(pin "D13"
		)
		(pin "D24"
		)
		(pin "A36"
		)
		(pin "B36"
		)
		(pin "D10"
		)
		(pin "J9"
		)
		(pin "G51"
		)
		(pin "G50"
		)
		(pin "J47"
		)
		(pin "E46"
		)
		(pin "A29"
		)
		(pin "C48"
		)
		(pin "F40"
		)
		(pin "D40"
		)
		(pin "B40"
		)
		(pin "D45"
		)
		(pin "J44"
		)
		(pin "J45"
		)
		(pin "K44"
		)
		(pin "J36"
		)
		(pin "J37"
		)
		(pin "C43"
		)
		(pin "E49"
		)
		(pin "C35"
		)
		(pin "A22"
		)
		(pin "J42"
		)
		(pin "B43"
		)
		(pin "B42"
		)
		(pin "A41"
		)
		(pin "G46"
		)
		(pin "L6"
		)
		(pin "L5"
		)
		(pin "H6"
		)
		(pin "K58"
		)
		(pin "H57"
		)
		(pin "E4"
		)
		(pin "F5"
		)
		(pin "F6"
		)
		(pin "H16"
		)
		(pin "D34"
		)
		(pin "A9"
		)
		(pin "H55"
		)
		(pin "L57"
		)
		(pin "L44"
		)
		(pin "F22"
		)
		(pin "B57"
		)
		(pin "E57"
		)
		(pin "J61"
		)
		(pin "K61"
		)
		(pin "F53"
		)
		(pin "B18"
		)
		(pin "L38"
		)
		(pin "D30"
		)
		(pin "J48"
		)
		(pin "K46"
		)
		(pin "K47"
		)
		(pin "E19"
		)
		(pin "E18"
		)
		(pin "C19"
		)
		(pin "F20"
		)
		(pin "C22"
		)
		(pin "B33"
		)
		(pin "J15"
		)
		(pin "C15"
		)
		(pin "C14"
		)
		(pin "C60"
		)
		(pin "K59"
		)
		(pin "J59"
		)
		(pin "A7"
		)
		(pin "D41"
		)
		(pin "G32"
		)
		(pin "H53"
		)
		(pin "E55"
		)
		(pin "B56"
		)
		(pin "J57"
		)
		(pin "C55"
		)
		(pin "B44"
		)
		(pin "E20"
		)
		(pin "E7"
		)
		(pin "F8"
		)
		(pin "A4"
		)
		(pin "D6"
		)
		(pin "B6"
		)
		(pin "K14"
		)
		(pin "K15"
		)
		(pin "E28"
		)
		(pin "G49"
		)
		(pin "D21"
		)
		(pin "B12"
		)
		(pin "K33"
		)
		(pin "J22"
		)
		(pin "F31"
		)
		(pin "F44"
		)
		(pin "E21"
		)
		(pin "L58"
		)
		(pin "L10"
		)
		(pin "A31"
		)
		(pin "B16"
		)
		(pin "D15"
		)
		(pin "A33"
		)
		(pin "C25"
		)
		(pin "G36"
		)
		(pin "H54"
		)
		(pin "K53"
		)
		(pin "K54"
		)
		(pin "G58"
		)
		(pin "A57"
		)
		(pin "F3"
		)
		(pin "A15"
		)
		(pin "A14"
		)
		(pin "J14"
		)
		(pin "A20"
		)
		(pin "J29"
		)
		(pin "J3"
		)
		(pin "J32"
		)
		(pin "J33"
		)
		(pin "H59"
		)
		(pin "G60"
		)
		(pin "J4"
		)
		(pin "B59"
		)
		(pin "A59"
		)
		(pin "K26"
		)
		(pin "K27"
		)
		(pin "D31"
		)
		(pin "L34"
		)
		(pin "F26"
		)
		(pin "L47"
		)
		(pin "L26"
		)
		(pin "H13"
		)
		(pin "H24"
		)
		(pin "G33"
		)
		(pin "G3"
		)
		(pin "F7"
		)
		(pin "C40"
		)
		(pin "B32"
		)
		(pin "B21"
		)
		(pin "K4"
		)
		(pin "K41"
		)
		(pin "B62"
		)
		(pin "C61"
		)
		(pin "A62"
		)
		(pin "G7"
		)
		(pin "L15"
		)
		(pin "E53"
		)
		(pin "D61"
		)
		(pin "E60"
		)
		(pin "L11"
		)
		(pin "J60"
		)
		(pin "A5"
		)
		(pin "E8"
		)
		(pin "E34"
		)
		(pin "F37"
		)
		(pin "F36"
		)
		(pin "E59"
		)
		(pin "F59"
		)
		(pin "A38"
		)
		(pin "E5"
		)
		(pin "B54"
		)
		(pin "B50"
		)
		(pin "C33"
		)
		(pin "H7"
		)
		(pin "J12"
		)
		(pin "A21"
		)
		(pin "C37"
		)
		(pin "H64"
		)
		(pin "A40"
		)
		(pin "G20"
		)
		(pin "A12"
		)
		(pin "E64"
		)
		(pin "H42"
		)
		(pin "G41"
		)
		(pin "G42"
		)
		(pin "J41"
		)
		(pin "G47"
		)
		(pin "E47"
		)
		(pin "E48"
		)
		(pin "C44"
		)
		(pin "E12"
		)
		(pin "G56"
		)
		(pin "E51"
		)
		(pin "E50"
		)
		(pin "K56"
		)
		(pin "C54"
		)
		(pin "G17"
		)
		(pin "L31"
		)
		(pin "F34"
		)
		(pin "D37"
		)
		(pin "D14"
		)
		(pin "D53"
		)
		(pin "H41"
		)
		(pin "H44"
		)
		(pin "D19"
		)
		(pin "D1"
		)
		(pin "A54"
		)
		(pin "C4"
		)
		(pin "D5"
		)
		(pin "G6"
		)
		(pin "J18"
		)
		(pin "H52"
		)
		(pin "C38"
		)
		(pin "A18"
		)
		(pin "F56"
		)
		(pin "A39"
		)
		(pin "B24"
		)
		(pin "C27"
		)
		(pin "L16"
		)
		(pin "L17"
		)
		(pin "L20"
		)
		(pin "L21"
		)
		(pin "G37"
		)
		(pin "A28"
		)
		(pin "B30"
		)
		(pin "C16"
		)
		(pin "G11"
		)
		(pin "G10"
		)
		(pin "F54"
		)
		(pin "H56"
		)
		(pin "H63"
		)
		(pin "F39"
		)
		(pin "C12"
		)
		(pin "D8"
		)
		(pin "C7"
		)
		(pin "H8"
		)
		(pin "G4"
		)
		(pin "H47"
		)
		(pin "H50"
		)
		(pin "K43"
		)
		(pin "H46"
		)
		(pin "H45"
		)
		(pin "B45"
		)
		(pin "J40"
		)
		(pin "J43"
		)
		(pin "F57"
		)
		(pin "A13"
		)
		(pin "A51"
		)
		(pin "A50"
		)
		(pin "C51"
		)
		(pin "A42"
		)
		(pin "C42"
		)
		(pin "C41"
		)
		(pin "F46"
		)
		(pin "L28"
		)
		(pin "L29"
		)
		(pin "F1"
		)
		(pin "H39"
		)
		(pin "H4"
		)
		(pin "K30"
		)
		(pin "K31"
		)
		(pin "F23"
		)
		(pin "D35"
		)
		(pin "L33"
		)
		(pin "L36"
		)
		(pin "H65"
		)
		(pin "L37"
		)
		(pin "L40"
		)
		(pin "C49"
		)
		(pin "K40"
		)
		(pin "F38"
		)
		(pin "G29"
		)
		(pin "H10"
		)
		(pin "L18"
		)
		(pin "A8"
		)
		(pin "E43"
		)
		(pin "G24"
		)
		(pin "L3"
		)
		(pin "L32"
		)
		(pin "J13"
		)
		(pin "J16"
		)
		(pin "K20"
		)
		(pin "H20"
		)
		(pin "F27"
		)
		(pin "F4"
		)
		(pin "C26"
		)
		(pin "A26"
		)
		(pin "K36"
		)
		(pin "J38"
		)
		(pin "J39"
		)
		(pin "D36"
		)
		(pin "G34"
		)
		(pin "K21"
		)
		(pin "D7"
		)
		(pin "C28"
		)
		(pin "C21"
		)
		(pin "J23"
		)
		(pin "G23"
		)
		(pin "L42"
		)
		(pin "C20"
		)
		(pin "H19"
		)
		(pin "H22"
		)
		(pin "H23"
		)
		(pin "H26"
		)
		(pin "E24"
		)
		(pin "E65"
		)
		(pin "C11"
		)
		(pin "C10"
		)
		(pin "F16"
		)
		(pin "F35"
		)
		(pin "C46"
		)
		(pin "G45"
		)
		(pin "F48"
		)
		(pin "F49"
		)
		(pin "G48"
		)
		(pin "G55"
		)
		(pin "B37"
		)
		(pin "E11"
		)
		(pin "C18"
		)
		(pin "D16"
		)
		(pin "D17"
		)
		(pin "A19"
		)
		(pin "K38"
		)
		(pin "K39"
		)
		(pin "A17"
		)
		(pin "D25"
		)
		(pin "B25"
		)
		(pin "H40"
		)
		(pin "G59"
		)
		(pin "K37"
		)
		(pin "C62"
		)
		(pin "J53"
		)
		(pin "K5"
		)
		(pin "L8"
		)
		(pin "E15"
		)
		(pin "E14"
		)
		(pin "D49"
		)
		(pin "B55"
		)
		(pin "C34"
		)
		(pin "H25"
		)
		(pin "K25"
		)
		(pin "F28"
		)
		(pin "F29"
		)
		(pin "F32"
		)
		(pin "L43"
		)
		(pin "L46"
		)
		(pin "L27"
		)
		(pin "B15"
		)
		(pin "L30"
		)
		(pin "G28"
		)
		(pin "A24"
		)
		(pin "H15"
		)
		(pin "H18"
		)
		(pin "E58"
		)
		(pin "B60"
		)
		(pin "A60"
		)
		(pin "D58"
		)
		(pin "G61"
		)
		(pin "H21"
		)
		(pin "K13"
		)
		(pin "H33"
		)
		(pin "K50"
		)
		(pin "G53"
		)
		(pin "G54"
		)
		(pin "H31"
		)
		(pin "H34"
		)
		(pin "H27"
		)
		(pin "H30"
		)
		(pin "C17"
		)
		(pin "E41"
		)
		(pin "E39"
		)
		(pin "E38"
		)
		(pin "H43"
		)
		(pin "L49"
		)
		(pin "L9"
		)
		(pin "L48"
		)
		(pin "J54"
		)
		(pin "J8"
		)
		(pin "K11"
		)
		(pin "J56"
		)
		(pin "J62"
		)
		(pin "B48"
		)
		(pin "B49"
		)
		(pin "B9"
		)
		(pin "J10"
		)
		(pin "B20"
		)
		(pin "D20"
		)
		(pin "C58"
		)
		(pin "C56"
		)
		(pin "H62"
		)
		(pin "K60"
		)
		(pin "L4"
		)
		(pin "K18"
		)
		(pin "K19"
		)
		(pin "L12"
		)
		(pin "L13"
		)
		(pin "L41"
		)
		(pin "G5"
		)
		(pin "G30"
		)
		(pin "J30"
		)
		(pin "F45"
		)
		(pin "E45"
		)
		(pin "E44"
		)
		(pin "G44"
		)
		(pin "D44"
		)
		(pin "A34"
		)
		(pin "A35"
		)
		(pin "H32"
		)
		(pin "A6"
		)
		(pin "C6"
		)
		(pin "G21"
		)
		(pin "J58"
		)
		(pin "H58"
		)
		(pin "K57"
		)
		(pin "E54"
		)
		(pin "K62"
		)
		(pin "J31"
		)
		(pin "K17"
		)
		(pin "F60"
		)
		(pin "C57"
		)
		(pin "E56"
		)
		(pin "F55"
		)
		(pin "D56"
		)
		(pin "L45"
		)
		(pin "J50"
		)
		(pin "D51"
		)
		(pin "E10"
		)
		(pin "C5"
		)
		(pin "B8"
		)
		(pin "L50"
		)
		(pin "G15"
		)
		(pin "G14"
		)
		(pin "D33"
		)
		(pin "K34"
		)
		(pin "K35"
		)
		(pin "L22"
		)
		(pin "E29"
		)
		(pin "J11"
		)
		(pin "E27"
		)
		(pin "E26"
		)
		(pin "K22"
		)
		(pin "K23"
		)
		(pin "G22"
		)
		(pin "G35"
		)
		(pin "F17"
		)
		(pin "F24"
		)
		(pin "F25"
		)
		(pin "A16"
		)
		(pin "A32"
		)
		(pin "G16"
		)
		(pin "G40"
		)
		(pin "H60"
		)
		(pin "H35"
		)
		(pin "H38"
		)
		(pin "C45"
		)
		(pin "D42"
		)
		(pin "D43"
		)
		(pin "D46"
		)
		(pin "F62"
		)
		(pin "F58"
		)
		(pin "D59"
		)
		(pin "B61"
		)
		(pin "H61"
		)
		(pin "L51"
		)
		(pin "F41"
		)
		(pin "G18"
		)
		(pin "H17"
		)
		(pin "G19"
		)
		(pin "C59"
		)
		(pin "B41"
		)
		(pin "A27"
		)
		(pin "D28"
		)
		(pin "E36"
		)
		(pin "L39"
		)
		(pin "E32"
		)
		(pin "L63"
		)
		(pin "A25"
		)
		(pin "A23"
		)
		(pin "C23"
		)
		(pin "K28"
		)
		(pin "G31"
		)
		(pin "J27"
		)
		(pin "H28"
		)
		(pin "H29"
		)
		(pin "K29"
		)
		(pin "F47"
		)
		(pin "D38"
		)
		(pin "D18"
		)
		(pin "H2"
		)
		(pin "F52"
		)
		(pin "F51"
		)
		(pin "A55"
		)
		(pin "L23"
		)
		(pin "J21"
		)
		(pin "J24"
		)
		(pin "B28"
		)
		(pin "C31"
		)
		(pin "F30"
		)
		(instances
			(project ""
				(path ""
					(reference "J1")
					(unit 1)
				)
			)
		)
	)
	(symbol
		(lib_id "antmicropower:GND")
		(at 360.68 228.6 0)
		(unit 1)
		(exclude_from_sim no)
		(in_bom yes)
		(on_board yes)
		(dnp no)
		(property "Reference" "#PWR0132"
			(at 360.68 234.95 0)
			(effects
				(font
					(size 1.27 1.27)
				)
				(justify left bottom)
				(hide yes)
			)
		)
		(property "Value" "GND"
			(at 360.68 232.41 0)
			(effects
				(font
					(size 1.27 1.27)
					(thickness 0.15)
				)
			)
		)
		(property "Footprint" ""
			(at 369.57 236.22 0)
			(effects
				(font
					(size 1.27 1.27)
					(thickness 0.15)
				)
				(justify left bottom)
				(hide yes)
			)
		)
		(property "Datasheet" ""
			(at 369.57 241.3 0)
			(effects
				(font
					(size 1.27 1.27)
					(thickness 0.15)
				)
				(justify left bottom)
				(hide yes)
			)
		)
		(property "Description" ""
			(at 360.68 228.6 0)
			(effects
				(font
					(size 1.27 1.27)
				)
				(hide yes)
			)
		)
		(property "Author" "Antmicro"
			(at 369.57 236.22 0)
			(effects
				(font
					(size 1.27 1.27)
					(thickness 0.15)
				)
				(justify left bottom)
				(hide yes)
			)
		)
		(property "License" "Apache-2.0"
			(at 369.57 238.76 0)
			(effects
				(font
					(size 1.27 1.27)
					(thickness 0.15)
				)
				(justify left bottom)
				(hide yes)
			)
		)
		(pin "1"
		)
		(instances
			(project "jetson-agx-thor-baseboard"
				(path ""
					(reference "#PWR0132")
					(unit 1)
				)
			)
		)
	)
	(symbol
		(lib_id "antmicroResistors0402:R_470R_0402")
		(at 290.83 219.71 90)
		(unit 1)
		(exclude_from_sim no)
		(in_bom yes)
		(on_board yes)
		(dnp no)
		(fields_autoplaced yes)
		(property "Reference" "R306"
			(at 293.37 215.9 90)
			(effects
				(font
					(size 1.27 1.27)
					(thickness 0.15)
				)
				(justify right)
			)
		)
		(property "Value" "R_470R_0402"
			(at 303.53 199.39 0)
			(effects
				(font
					(size 1.27 1.27)
					(thickness 0.15)
				)
				(justify left bottom)
				(hide yes)
			)
		)
		(property "Footprint" "antmicro-footprints:R_0402_1005Metric"
			(at 306.07 199.39 0)
			(effects
				(font
					(size 1.27 1.27)
					(thickness 0.15)
				)
				(justify left bottom)
				(hide yes)
			)
		)
		(property "Datasheet" "https://www.bourns.com/docs/product-datasheets/cr.pdf"
			(at 308.61 199.39 0)
			(effects
				(font
					(size 1.27 1.27)
					(thickness 0.15)
				)
				(justify left bottom)
				(hide yes)
			)
		)
		(property "Description" "SMD Chip Resistor, 470 ohm, ± 1%, 62.5 mW, 0402 [1005 Metric], Thick Film, General Purpose"
			(at 290.83 219.71 0)
			(effects
				(font
					(size 1.27 1.27)
				)
				(hide yes)
			)
		)
		(property "MPN" "CR0402-FX-4700GLF"
			(at 311.15 199.39 0)
			(effects
				(font
					(size 1.27 1.27)
					(thickness 0.15)
				)
				(justify left bottom)
				(hide yes)
			)
		)
		(property "Manufacturer" "Bourns"
			(at 313.69 199.39 0)
			(effects
				(font
					(size 1.27 1.27)
					(thickness 0.15)
				)
				(justify left bottom)
				(hide yes)
			)
		)
		(property "License" "Apache-2.0"
			(at 316.23 199.39 0)
			(effects
				(font
					(size 1.27 1.27)
					(thickness 0.15)
				)
				(justify left bottom)
				(hide yes)
			)
		)
		(property "Author" "Antmicro"
			(at 318.77 199.39 0)
			(effects
				(font
					(size 1.27 1.27)
					(thickness 0.15)
				)
				(justify left bottom)
				(hide yes)
			)
		)
		(property "Val" "470R"
			(at 293.37 218.44 90)
			(effects
				(font
					(size 1.27 1.27)
					(thickness 0.15)
				)
				(justify right)
			)
		)
		(property "Tolerance" "1%"
			(at 300.99 199.39 0)
			(effects
				(font
					(size 1.27 1.27)
				)
				(justify left bottom)
				(hide yes)
			)
		)
		(pin "1"
		)
		(pin "2"
		)
		(instances
			(project "jetson-agx-thor-baseboard"
				(path ""
					(reference "R306")
					(unit 1)
				)
			)
		)
	)
	(symbol
		(lib_id "antmicropower:GND")
		(at 109.22 210.82 0)
		(unit 1)
		(exclude_from_sim no)
		(in_bom yes)
		(on_board yes)
		(dnp no)
		(property "Reference" "#PWR0150"
			(at 109.22 217.17 0)
			(effects
				(font
					(size 1.27 1.27)
				)
				(justify left bottom)
				(hide yes)
			)
		)
		(property "Value" "GND"
			(at 109.22 214.63 0)
			(effects
				(font
					(size 1.27 1.27)
					(thickness 0.15)
				)
			)
		)
		(property "Footprint" ""
			(at 118.11 218.44 0)
			(effects
				(font
					(size 1.27 1.27)
					(thickness 0.15)
				)
				(justify left bottom)
				(hide yes)
			)
		)
		(property "Datasheet" ""
			(at 118.11 223.52 0)
			(effects
				(font
					(size 1.27 1.27)
					(thickness 0.15)
				)
				(justify left bottom)
				(hide yes)
			)
		)
		(property "Description" ""
			(at 109.22 210.82 0)
			(effects
				(font
					(size 1.27 1.27)
				)
				(hide yes)
			)
		)
		(property "Author" "Antmicro"
			(at 118.11 218.44 0)
			(effects
				(font
					(size 1.27 1.27)
					(thickness 0.15)
				)
				(justify left bottom)
				(hide yes)
			)
		)
		(property "License" "Apache-2.0"
			(at 118.11 220.98 0)
			(effects
				(font
					(size 1.27 1.27)
					(thickness 0.15)
				)
				(justify left bottom)
				(hide yes)
			)
		)
		(pin "1"
		)
		(instances
			(project "jetson-agx-thor-baseboard"
				(path ""
					(reference "#PWR0150")
					(unit 1)
				)
			)
		)
	)
	(symbol
		(lib_id "antmicroTestPoints:TP_0.75mm_SMD")
		(at 251.46 86.36 0)
		(unit 1)
		(exclude_from_sim no)
		(in_bom no)
		(on_board yes)
		(dnp no)
		(fields_autoplaced yes)
		(property "Reference" "TP49"
			(at 256.54 86.36 0)
			(effects
				(font
					(size 1.27 1.27)
					(thickness 0.15)
				)
				(justify left)
			)
		)
		(property "Value" "TP_0.75mm_SMD"
			(at 261.62 90.17 0)
			(effects
				(font
					(size 1.27 1.27)
					(thickness 0.15)
				)
				(justify left bottom)
				(hide yes)
			)
		)
		(property "Footprint" "antmicro-footprints:TP_SMD_0.75mm"
			(at 261.62 92.71 0)
			(effects
				(font
					(size 1.27 1.27)
					(thickness 0.15)
				)
				(justify left bottom)
				(hide yes)
			)
		)
		(property "Datasheet" ""
			(at 269.24 99.06 0)
			(effects
				(font
					(size 1.27 1.27)
					(thickness 0.15)
				)
				(justify left bottom)
				(hide yes)
			)
		)
		(property "Description" "SMT test point"
			(at 251.46 86.36 0)
			(effects
				(font
					(size 1.27 1.27)
				)
				(hide yes)
			)
		)
		(property "MPN" ""
			(at 262.255 97.79 0)
			(effects
				(font
					(size 1.27 1.27)
					(thickness 0.15)
				)
				(justify left bottom)
				(hide yes)
			)
		)
		(property "Manufacturer" ""
			(at 262.255 92.71 0)
			(effects
				(font
					(size 1.27 1.27)
					(thickness 0.15)
				)
				(justify left bottom)
				(hide yes)
			)
		)
		(property "Author" "Antmicro"
			(at 261.62 95.25 0)
			(effects
				(font
					(size 1.27 1.27)
					(thickness 0.15)
				)
				(justify left bottom)
				(hide yes)
			)
		)
		(property "License" "Apache-2.0"
			(at 261.62 97.79 0)
			(effects
				(font
					(size 1.27 1.27)
					(thickness 0.15)
				)
				(justify left bottom)
				(hide yes)
			)
		)
		(pin "1"
		)
		(instances
			(project "jetson-agx-thor-baseboard"
				(path ""
					(reference "TP49")
					(unit 1)
				)
			)
		)
	)
	(symbol
		(lib_id "antmicroTestPoints:TP_0.75mm_SMD")
		(at 30.48 157.48 180)
		(unit 1)
		(exclude_from_sim no)
		(in_bom no)
		(on_board yes)
		(dnp no)
		(fields_autoplaced yes)
		(property "Reference" "TP85"
			(at 26.67 157.48 0)
			(effects
				(font
					(size 1.27 1.27)
					(thickness 0.15)
				)
				(justify left)
			)
		)
		(property "Value" "TP_0.75mm_SMD"
			(at 20.32 153.67 0)
			(effects
				(font
					(size 1.27 1.27)
					(thickness 0.15)
				)
				(justify left bottom)
				(hide yes)
			)
		)
		(property "Footprint" "antmicro-footprints:TP_SMD_0.75mm"
			(at 20.32 151.13 0)
			(effects
				(font
					(size 1.27 1.27)
					(thickness 0.15)
				)
				(justify left bottom)
				(hide yes)
			)
		)
		(property "Datasheet" ""
			(at 12.7 144.78 0)
			(effects
				(font
					(size 1.27 1.27)
					(thickness 0.15)
				)
				(justify left bottom)
				(hide yes)
			)
		)
		(property "Description" "SMT test point"
			(at 30.48 157.48 0)
			(effects
				(font
					(size 1.27 1.27)
				)
				(hide yes)
			)
		)
		(property "MPN" ""
			(at 19.685 146.05 0)
			(effects
				(font
					(size 1.27 1.27)
					(thickness 0.15)
				)
				(justify left bottom)
				(hide yes)
			)
		)
		(property "Manufacturer" ""
			(at 19.685 151.13 0)
			(effects
				(font
					(size 1.27 1.27)
					(thickness 0.15)
				)
				(justify left bottom)
				(hide yes)
			)
		)
		(property "Author" "Antmicro"
			(at 20.32 148.59 0)
			(effects
				(font
					(size 1.27 1.27)
					(thickness 0.15)
				)
				(justify left bottom)
				(hide yes)
			)
		)
		(property "License" "Apache-2.0"
			(at 20.32 146.05 0)
			(effects
				(font
					(size 1.27 1.27)
					(thickness 0.15)
				)
				(justify left bottom)
				(hide yes)
			)
		)
		(pin "1"
		)
		(instances
			(project "jetson-agx-thor-baseboard"
				(path ""
					(reference "TP85")
					(unit 1)
				)
			)
		)
	)
	(symbol
		(lib_id "antmicroResistors0402:R_10k_0402")
		(at 156.21 187.96 90)
		(unit 1)
		(exclude_from_sim no)
		(in_bom yes)
		(on_board yes)
		(dnp no)
		(property "Reference" "R224"
			(at 157.48 184.15 90)
			(effects
				(font
					(size 1.27 1.27)
					(thickness 0.15)
				)
				(justify right)
			)
		)
		(property "Value" "R_10k_0402"
			(at 168.91 167.64 0)
			(effects
				(font
					(size 1.27 1.27)
					(thickness 0.15)
				)
				(justify left bottom)
				(hide yes)
			)
		)
		(property "Footprint" "antmicro-footprints:R_0402_1005Metric"
			(at 171.45 167.64 0)
			(effects
				(font
					(size 1.27 1.27)
					(thickness 0.15)
				)
				(justify left bottom)
				(hide yes)
			)
		)
		(property "Datasheet" "https://www.bourns.com/docs/product-datasheets/cr.pdf"
			(at 173.99 167.64 0)
			(effects
				(font
					(size 1.27 1.27)
					(thickness 0.15)
				)
				(justify left bottom)
				(hide yes)
			)
		)
		(property "Description" "SMD Chip Resistor, 10 kohm, ± 1%, 62.5 mW, 0402 [1005 Metric], Thick Film, General Purpose"
			(at 156.21 187.96 0)
			(effects
				(font
					(size 1.27 1.27)
				)
				(hide yes)
			)
		)
		(property "MPN" "CR0402-FX-1002GLF"
			(at 176.53 167.64 0)
			(effects
				(font
					(size 1.27 1.27)
					(thickness 0.15)
				)
				(justify left bottom)
				(hide yes)
			)
		)
		(property "Manufacturer" "Bourns"
			(at 179.07 167.64 0)
			(effects
				(font
					(size 1.27 1.27)
					(thickness 0.15)
				)
				(justify left bottom)
				(hide yes)
			)
		)
		(property "License" "Apache-2.0"
			(at 181.61 167.64 0)
			(effects
				(font
					(size 1.27 1.27)
					(thickness 0.15)
				)
				(justify left bottom)
				(hide yes)
			)
		)
		(property "Author" "Antmicro"
			(at 184.15 167.64 0)
			(effects
				(font
					(size 1.27 1.27)
					(thickness 0.15)
				)
				(justify left bottom)
				(hide yes)
			)
		)
		(property "Val" "10k"
			(at 157.48 186.69 90)
			(effects
				(font
					(size 1.27 1.27)
					(thickness 0.15)
				)
				(justify right)
			)
		)
		(property "Tolerance" "1%"
			(at 166.37 167.64 0)
			(effects
				(font
					(size 1.27 1.27)
				)
				(justify left bottom)
				(hide yes)
			)
		)
		(pin "2"
		)
		(pin "1"
		)
		(instances
			(project "jetson-agx-thor-baseboard"
				(path ""
					(reference "R224")
					(unit 1)
				)
			)
		)
	)
	(symbol
		(lib_id "antmicroCapacitors0402:C_1u_25V_0402")
		(at 128.27 227.33 90)
		(unit 1)
		(exclude_from_sim no)
		(in_bom yes)
		(on_board yes)
		(dnp no)
		(property "Reference" "C251"
			(at 120.904 223.774 90)
			(effects
				(font
					(size 1.27 1.27)
					(thickness 0.15)
				)
				(justify right)
			)
		)
		(property "Value" "C_1u_25V_0402"
			(at 138.43 207.01 0)
			(effects
				(font
					(size 1.27 1.27)
					(thickness 0.15)
				)
				(justify left bottom)
				(hide yes)
			)
		)
		(property "Footprint" "antmicro-footprints:C_0402_1005Metric"
			(at 140.97 207.01 0)
			(effects
				(font
					(size 1.27 1.27)
					(thickness 0.15)
				)
				(justify left bottom)
				(hide yes)
			)
		)
		(property "Datasheet" "https://www.murata.com/products/productdetail?partno=GRM155R61E105KE11%23"
			(at 143.51 207.01 0)
			(effects
				(font
					(size 1.27 1.27)
					(thickness 0.15)
				)
				(justify left bottom)
				(hide yes)
			)
		)
		(property "Description" "SMD Multilayer Ceramic Capacitor, 1 µF, 25 V, 0402 [1005 Metric], ± 10%, X5R, GRM Series"
			(at 128.27 227.33 0)
			(effects
				(font
					(size 1.27 1.27)
				)
				(hide yes)
			)
		)
		(property "MPN" "GRM155R61E105KE11J"
			(at 146.05 207.01 0)
			(effects
				(font
					(size 1.27 1.27)
					(thickness 0.15)
				)
				(justify left bottom)
				(hide yes)
			)
		)
		(property "Manufacturer" "Murata"
			(at 148.59 207.01 0)
			(effects
				(font
					(size 1.27 1.27)
					(thickness 0.15)
				)
				(justify left bottom)
				(hide yes)
			)
		)
		(property "License" "Apache-2.0"
			(at 151.13 207.01 0)
			(effects
				(font
					(size 1.27 1.27)
					(thickness 0.15)
				)
				(justify left bottom)
				(hide yes)
			)
		)
		(property "Author" "Antmicro"
			(at 153.67 207.01 0)
			(effects
				(font
					(size 1.27 1.27)
					(thickness 0.15)
				)
				(justify left bottom)
				(hide yes)
			)
		)
		(property "Val" "1u"
			(at 120.904 226.314 90)
			(effects
				(font
					(size 1.27 1.27)
					(thickness 0.15)
				)
				(justify right)
			)
		)
		(property "Voltage" "25V"
			(at 156.21 207.01 0)
			(effects
				(font
					(size 1.27 1.27)
				)
				(justify left bottom)
				(hide yes)
			)
		)
		(property "Dielectric" "X5R"
			(at 158.75 207.01 0)
			(effects
				(font
					(size 1.27 1.27)
				)
				(justify left bottom)
				(hide yes)
			)
		)
		(pin "2"
		)
		(pin "1"
		)
		(instances
			(project "jetson-agx-thor-baseboard"
				(path ""
					(reference "C251")
					(unit 1)
				)
			)
		)
	)
	(symbol
		(lib_id "antmicropower:+3V3_AON")
		(at 166.37 180.34 0)
		(unit 1)
		(exclude_from_sim no)
		(in_bom yes)
		(on_board yes)
		(dnp no)
		(fields_autoplaced yes)
		(property "Reference" "#PWR0109"
			(at 166.37 184.15 0)
			(effects
				(font
					(size 1.27 1.27)
				)
				(hide yes)
			)
		)
		(property "Value" "+5V_AON"
			(at 166.37 175.26 0)
			(effects
				(font
					(size 1.27 1.27)
				)
			)
		)
		(property "Footprint" ""
			(at 166.37 180.34 0)
			(effects
				(font
					(size 1.27 1.27)
				)
				(hide yes)
			)
		)
		(property "Datasheet" ""
			(at 166.37 180.34 0)
			(effects
				(font
					(size 1.27 1.27)
				)
				(hide yes)
			)
		)
		(property "Description" ""
			(at 166.37 180.34 0)
			(effects
				(font
					(size 1.27 1.27)
				)
				(hide yes)
			)
		)
		(pin "1"
		)
		(instances
			(project "jetson-agx-thor-baseboard"
				(path ""
					(reference "#PWR0109")
					(unit 1)
				)
			)
		)
	)
	(symbol
		(lib_id "antmicroResistors0402:R_10k_0402")
		(at 199.39 247.65 90)
		(unit 1)
		(exclude_from_sim no)
		(in_bom yes)
		(on_board yes)
		(dnp no)
		(fields_autoplaced yes)
		(property "Reference" "R305"
			(at 201.93 243.84 90)
			(effects
				(font
					(size 1.27 1.27)
					(thickness 0.15)
				)
				(justify right)
			)
		)
		(property "Value" "R_10k_0402"
			(at 212.09 227.33 0)
			(effects
				(font
					(size 1.27 1.27)
					(thickness 0.15)
				)
				(justify left bottom)
				(hide yes)
			)
		)
		(property "Footprint" "antmicro-footprints:R_0402_1005Metric"
			(at 214.63 227.33 0)
			(effects
				(font
					(size 1.27 1.27)
					(thickness 0.15)
				)
				(justify left bottom)
				(hide yes)
			)
		)
		(property "Datasheet" "https://www.bourns.com/docs/product-datasheets/cr.pdf"
			(at 217.17 227.33 0)
			(effects
				(font
					(size 1.27 1.27)
					(thickness 0.15)
				)
				(justify left bottom)
				(hide yes)
			)
		)
		(property "Description" "SMD Chip Resistor, 10 kohm, ± 1%, 62.5 mW, 0402 [1005 Metric], Thick Film, General Purpose"
			(at 229.87 227.33 0)
			(effects
				(font
					(size 1.27 1.27)
				)
				(justify left bottom)
				(hide yes)
			)
		)
		(property "MPN" "CR0402-FX-1002GLF"
			(at 219.71 227.33 0)
			(effects
				(font
					(size 1.27 1.27)
					(thickness 0.15)
				)
				(justify left bottom)
				(hide yes)
			)
		)
		(property "Manufacturer" "Bourns"
			(at 222.25 227.33 0)
			(effects
				(font
					(size 1.27 1.27)
					(thickness 0.15)
				)
				(justify left bottom)
				(hide yes)
			)
		)
		(property "License" "Apache-2.0"
			(at 224.79 227.33 0)
			(effects
				(font
					(size 1.27 1.27)
					(thickness 0.15)
				)
				(justify left bottom)
				(hide yes)
			)
		)
		(property "Author" "Antmicro"
			(at 227.33 227.33 0)
			(effects
				(font
					(size 1.27 1.27)
					(thickness 0.15)
				)
				(justify left bottom)
				(hide yes)
			)
		)
		(property "Val" "10k"
			(at 201.93 246.38 90)
			(effects
				(font
					(size 1.27 1.27)
					(thickness 0.15)
				)
				(justify right)
			)
		)
		(property "Tolerance" "1%"
			(at 209.55 227.33 0)
			(effects
				(font
					(size 1.27 1.27)
				)
				(justify left bottom)
				(hide yes)
			)
		)
		(pin "1"
		)
		(pin "2"
		)
		(instances
			(project ""
				(path ""
					(reference "R305")
					(unit 1)
				)
			)
		)
	)
	(symbol
		(lib_id "antmicropower:+3V3_AON")
		(at 60.96 144.78 0)
		(unit 1)
		(exclude_from_sim no)
		(in_bom yes)
		(on_board yes)
		(dnp no)
		(fields_autoplaced yes)
		(property "Reference" "#PWR0665"
			(at 60.96 148.59 0)
			(effects
				(font
					(size 1.27 1.27)
				)
				(hide yes)
			)
		)
		(property "Value" "+3V3_AON"
			(at 60.96 139.7 0)
			(effects
				(font
					(size 1.27 1.27)
				)
			)
		)
		(property "Footprint" ""
			(at 60.96 144.78 0)
			(effects
				(font
					(size 1.27 1.27)
				)
				(hide yes)
			)
		)
		(property "Datasheet" ""
			(at 60.96 144.78 0)
			(effects
				(font
					(size 1.27 1.27)
				)
				(hide yes)
			)
		)
		(property "Description" ""
			(at 60.96 144.78 0)
			(effects
				(font
					(size 1.27 1.27)
				)
				(hide yes)
			)
		)
		(pin "1"
		)
		(instances
			(project "jetson-agx-thor-baseboard"
				(path ""
					(reference "#PWR0665")
					(unit 1)
				)
			)
		)
	)
	(symbol
		(lib_id "antmicropower:GND")
		(at 38.1 161.29 0)
		(unit 1)
		(exclude_from_sim no)
		(in_bom yes)
		(on_board yes)
		(dnp no)
		(property "Reference" "#PWR076"
			(at 46.99 163.83 0)
			(effects
				(font
					(size 1.27 1.27)
					(thickness 0.15)
				)
				(justify left bottom)
				(hide yes)
			)
		)
		(property "Value" "GND"
			(at 38.1 165.1 0)
			(effects
				(font
					(size 1.27 1.27)
					(thickness 0.15)
				)
			)
		)
		(property "Footprint" ""
			(at 46.99 168.91 0)
			(effects
				(font
					(size 1.27 1.27)
					(thickness 0.15)
				)
				(justify left bottom)
				(hide yes)
			)
		)
		(property "Datasheet" ""
			(at 46.99 173.99 0)
			(effects
				(font
					(size 1.27 1.27)
					(thickness 0.15)
				)
				(justify left bottom)
				(hide yes)
			)
		)
		(property "Description" ""
			(at 38.1 161.29 0)
			(effects
				(font
					(size 1.27 1.27)
				)
				(hide yes)
			)
		)
		(property "Author" "Antmicro"
			(at 46.99 168.91 0)
			(effects
				(font
					(size 1.27 1.27)
					(thickness 0.15)
				)
				(justify left bottom)
				(hide yes)
			)
		)
		(property "License" "Apache-2.0"
			(at 46.99 171.45 0)
			(effects
				(font
					(size 1.27 1.27)
					(thickness 0.15)
				)
				(justify left bottom)
				(hide yes)
			)
		)
		(pin "1"
		)
		(instances
			(project "jetson-agx-thor-baseboard"
				(path ""
					(reference "#PWR076")
					(unit 1)
				)
			)
		)
	)
	(symbol
		(lib_id "antmicroResistors0603:R_0R_22.4A_0603")
		(at 71.12 31.75 0)
		(unit 1)
		(exclude_from_sim no)
		(in_bom yes)
		(on_board yes)
		(dnp no)
		(property "Reference" "R76"
			(at 73.66 27.432 0)
			(effects
				(font
					(size 1.27 1.27)
				)
			)
		)
		(property "Value" "R_0R_22.4A_0603"
			(at 73.66 22.86 0)
			(effects
				(font
					(size 1.27 1.27)
					(thickness 0.15)
				)
				(hide yes)
			)
		)
		(property "Footprint" "antmicro-footprints:R_0603_1608Metric"
			(at 86.36 41.91 0)
			(effects
				(font
					(size 1.27 1.27)
					(thickness 0.15)
				)
				(justify left bottom)
				(hide yes)
			)
		)
		(property "Datasheet" "https://fscdn.rohm.com/en/products/databook/datasheet/passive/resistor/chip_resistor/pmr-jpw-e.pdf"
			(at 86.36 44.45 0)
			(effects
				(font
					(size 1.27 1.27)
					(thickness 0.15)
				)
				(justify left bottom)
				(hide yes)
			)
		)
		(property "Description" "SMD Chip Resistor"
			(at 71.12 31.75 0)
			(effects
				(font
					(size 1.27 1.27)
				)
				(hide yes)
			)
		)
		(property "Manufacturer" "ROHM Semiconductor"
			(at 86.36 49.53 0)
			(effects
				(font
					(size 1.27 1.27)
					(thickness 0.15)
				)
				(justify left bottom)
				(hide yes)
			)
		)
		(property "MPN" "PMR03EZPJ000"
			(at 86.36 46.99 0)
			(effects
				(font
					(size 1.27 1.27)
					(thickness 0.15)
				)
				(justify left bottom)
				(hide yes)
			)
		)
		(property "Val" "0R"
			(at 73.66 29.21 0)
			(effects
				(font
					(size 1.27 1.27)
					(thickness 0.15)
				)
			)
		)
		(property "Author" "Antmicro"
			(at 86.36 54.61 0)
			(effects
				(font
					(size 1.27 1.27)
					(thickness 0.15)
				)
				(justify left bottom)
				(hide yes)
			)
		)
		(property "License" "Apache-2.0"
			(at 86.36 57.15 0)
			(effects
				(font
					(size 1.27 1.27)
					(thickness 0.15)
				)
				(justify left bottom)
				(hide yes)
			)
		)
		(property "Max. Curr." "22.4A"
			(at 73.66 34.29 0)
			(effects
				(font
					(size 1.27 1.27)
					(thickness 0.15)
				)
			)
		)
		(property "Tolerance" "template_tolerance"
			(at 91.44 41.91 0)
			(effects
				(font
					(size 1.27 1.27)
				)
				(justify left bottom)
				(hide yes)
			)
		)
		(pin "1"
		)
		(pin "2"
		)
		(instances
			(project "jetson-agx-thor-baseboard"
				(path ""
					(reference "R76")
					(unit 1)
				)
			)
		)
	)
	(symbol
		(lib_id "antmicropower:GND")
		(at 106.68 50.8 0)
		(unit 1)
		(exclude_from_sim no)
		(in_bom yes)
		(on_board yes)
		(dnp no)
		(fields_autoplaced yes)
		(property "Reference" "#PWR0631"
			(at 115.57 53.34 0)
			(effects
				(font
					(size 1.27 1.27)
					(thickness 0.15)
				)
				(justify left bottom)
				(hide yes)
			)
		)
		(property "Value" "GND"
			(at 106.68 55.88 0)
			(effects
				(font
					(size 1.27 1.27)
					(thickness 0.15)
				)
			)
		)
		(property "Footprint" ""
			(at 115.57 58.42 0)
			(effects
				(font
					(size 1.27 1.27)
					(thickness 0.15)
				)
				(justify left bottom)
				(hide yes)
			)
		)
		(property "Datasheet" ""
			(at 115.57 63.5 0)
			(effects
				(font
					(size 1.27 1.27)
					(thickness 0.15)
				)
				(justify left bottom)
				(hide yes)
			)
		)
		(property "Description" ""
			(at 106.68 50.8 0)
			(effects
				(font
					(size 1.27 1.27)
				)
				(hide yes)
			)
		)
		(property "Author" "Antmicro"
			(at 115.57 58.42 0)
			(effects
				(font
					(size 1.27 1.27)
					(thickness 0.15)
				)
				(justify left bottom)
				(hide yes)
			)
		)
		(property "License" "Apache-2.0"
			(at 115.57 60.96 0)
			(effects
				(font
					(size 1.27 1.27)
					(thickness 0.15)
				)
				(justify left bottom)
				(hide yes)
			)
		)
		(pin "1"
		)
		(instances
			(project "jetson-agx-thor-baseboard"
				(path ""
					(reference "#PWR0631")
					(unit 1)
				)
			)
		)
	)
	(symbol
		(lib_id "antmicroTestPoints:TP_0.75mm_SMD")
		(at 336.55 231.14 90)
		(unit 1)
		(exclude_from_sim no)
		(in_bom no)
		(on_board yes)
		(dnp no)
		(property "Reference" "TP86"
			(at 338.582 225.806 90)
			(effects
				(font
					(size 1.27 1.27)
					(thickness 0.15)
				)
				(justify left)
			)
		)
		(property "Value" "TP_0.75mm_SMD"
			(at 340.36 220.98 0)
			(effects
				(font
					(size 1.27 1.27)
					(thickness 0.15)
				)
				(justify left bottom)
				(hide yes)
			)
		)
		(property "Footprint" "antmicro-footprints:TP_SMD_0.75mm"
			(at 342.9 220.98 0)
			(effects
				(font
					(size 1.27 1.27)
					(thickness 0.15)
				)
				(justify left bottom)
				(hide yes)
			)
		)
		(property "Datasheet" ""
			(at 349.25 213.36 0)
			(effects
				(font
					(size 1.27 1.27)
					(thickness 0.15)
				)
				(justify left bottom)
				(hide yes)
			)
		)
		(property "Description" "SMT test point"
			(at 336.55 231.14 0)
			(effects
				(font
					(size 1.27 1.27)
				)
				(hide yes)
			)
		)
		(property "MPN" ""
			(at 347.98 220.345 0)
			(effects
				(font
					(size 1.27 1.27)
					(thickness 0.15)
				)
				(justify left bottom)
				(hide yes)
			)
		)
		(property "Manufacturer" ""
			(at 342.9 220.345 0)
			(effects
				(font
					(size 1.27 1.27)
					(thickness 0.15)
				)
				(justify left bottom)
				(hide yes)
			)
		)
		(property "Author" "Antmicro"
			(at 345.44 220.98 0)
			(effects
				(font
					(size 1.27 1.27)
					(thickness 0.15)
				)
				(justify left bottom)
				(hide yes)
			)
		)
		(property "License" "Apache-2.0"
			(at 347.98 220.98 0)
			(effects
				(font
					(size 1.27 1.27)
					(thickness 0.15)
				)
				(justify left bottom)
				(hide yes)
			)
		)
		(pin "1"
		)
		(instances
			(project "jetson-agx-thor-baseboard"
				(path ""
					(reference "TP86")
					(unit 1)
				)
			)
		)
	)
	(symbol
		(lib_id "antmicroTestPoints:TP_0.75mm_SMD")
		(at 193.04 78.74 0)
		(mirror y)
		(unit 1)
		(exclude_from_sim no)
		(in_bom no)
		(on_board yes)
		(dnp no)
		(fields_autoplaced yes)
		(property "Reference" "TP60"
			(at 187.96 78.74 0)
			(effects
				(font
					(size 1.27 1.27)
					(thickness 0.15)
				)
				(justify left)
			)
		)
		(property "Value" "TP_0.75mm_SMD"
			(at 182.88 82.55 0)
			(effects
				(font
					(size 1.27 1.27)
					(thickness 0.15)
				)
				(justify left bottom)
				(hide yes)
			)
		)
		(property "Footprint" "antmicro-footprints:TP_SMD_0.75mm"
			(at 182.88 85.09 0)
			(effects
				(font
					(size 1.27 1.27)
					(thickness 0.15)
				)
				(justify left bottom)
				(hide yes)
			)
		)
		(property "Datasheet" ""
			(at 175.26 91.44 0)
			(effects
				(font
					(size 1.27 1.27)
					(thickness 0.15)
				)
				(justify left bottom)
				(hide yes)
			)
		)
		(property "Description" "SMT test point"
			(at 193.04 78.74 0)
			(effects
				(font
					(size 1.27 1.27)
				)
				(hide yes)
			)
		)
		(property "MPN" ""
			(at 182.245 90.17 0)
			(effects
				(font
					(size 1.27 1.27)
					(thickness 0.15)
				)
				(justify left bottom)
				(hide yes)
			)
		)
		(property "Manufacturer" ""
			(at 182.245 85.09 0)
			(effects
				(font
					(size 1.27 1.27)
					(thickness 0.15)
				)
				(justify left bottom)
				(hide yes)
			)
		)
		(property "Author" "Antmicro"
			(at 182.88 87.63 0)
			(effects
				(font
					(size 1.27 1.27)
					(thickness 0.15)
				)
				(justify left bottom)
				(hide yes)
			)
		)
		(property "License" "Apache-2.0"
			(at 182.88 90.17 0)
			(effects
				(font
					(size 1.27 1.27)
					(thickness 0.15)
				)
				(justify left bottom)
				(hide yes)
			)
		)
		(pin "1"
		)
		(instances
			(project "jetson-agx-thor-baseboard"
				(path ""
					(reference "TP60")
					(unit 1)
				)
			)
		)
	)
	(symbol
		(lib_id "antmicroResistors0402:R_10k_0402")
		(at 203.2 271.78 90)
		(unit 1)
		(exclude_from_sim no)
		(in_bom yes)
		(on_board yes)
		(dnp no)
		(property "Reference" "R287"
			(at 204.47 267.97 90)
			(effects
				(font
					(size 1.27 1.27)
					(thickness 0.15)
				)
				(justify right)
			)
		)
		(property "Value" "R_10k_0402"
			(at 215.9 251.46 0)
			(effects
				(font
					(size 1.27 1.27)
					(thickness 0.15)
				)
				(justify left bottom)
				(hide yes)
			)
		)
		(property "Footprint" "antmicro-footprints:R_0402_1005Metric"
			(at 218.44 251.46 0)
			(effects
				(font
					(size 1.27 1.27)
					(thickness 0.15)
				)
				(justify left bottom)
				(hide yes)
			)
		)
		(property "Datasheet" "https://www.bourns.com/docs/product-datasheets/cr.pdf"
			(at 220.98 251.46 0)
			(effects
				(font
					(size 1.27 1.27)
					(thickness 0.15)
				)
				(justify left bottom)
				(hide yes)
			)
		)
		(property "Description" "SMD Chip Resistor, 10 kohm, ± 1%, 62.5 mW, 0402 [1005 Metric], Thick Film, General Purpose"
			(at 203.2 271.78 0)
			(effects
				(font
					(size 1.27 1.27)
				)
				(hide yes)
			)
		)
		(property "MPN" "CR0402-FX-1002GLF"
			(at 223.52 251.46 0)
			(effects
				(font
					(size 1.27 1.27)
					(thickness 0.15)
				)
				(justify left bottom)
				(hide yes)
			)
		)
		(property "Manufacturer" "Bourns"
			(at 226.06 251.46 0)
			(effects
				(font
					(size 1.27 1.27)
					(thickness 0.15)
				)
				(justify left bottom)
				(hide yes)
			)
		)
		(property "License" "Apache-2.0"
			(at 228.6 251.46 0)
			(effects
				(font
					(size 1.27 1.27)
					(thickness 0.15)
				)
				(justify left bottom)
				(hide yes)
			)
		)
		(property "Author" "Antmicro"
			(at 231.14 251.46 0)
			(effects
				(font
					(size 1.27 1.27)
					(thickness 0.15)
				)
				(justify left bottom)
				(hide yes)
			)
		)
		(property "Val" "10k"
			(at 204.47 270.51 90)
			(effects
				(font
					(size 1.27 1.27)
					(thickness 0.15)
				)
				(justify right)
			)
		)
		(property "Tolerance" "1%"
			(at 213.36 251.46 0)
			(effects
				(font
					(size 1.27 1.27)
				)
				(justify left bottom)
				(hide yes)
			)
		)
		(pin "2"
		)
		(pin "1"
		)
		(instances
			(project "jetson-agx-thor-baseboard"
				(path ""
					(reference "R287")
					(unit 1)
				)
			)
		)
	)
	(symbol
		(lib_id "antmicroTestPoints:TP_0.75mm_SMD")
		(at 83.82 245.11 90)
		(unit 1)
		(exclude_from_sim no)
		(in_bom no)
		(on_board yes)
		(dnp no)
		(property "Reference" "TP118"
			(at 83.82 240.03 90)
			(effects
				(font
					(size 1.27 1.27)
					(thickness 0.15)
				)
			)
		)
		(property "Value" "TP_0.75mm_SMD"
			(at 87.63 234.95 0)
			(effects
				(font
					(size 1.27 1.27)
					(thickness 0.15)
				)
				(justify left bottom)
				(hide yes)
			)
		)
		(property "Footprint" "antmicro-footprints:TP_SMD_0.75mm"
			(at 90.17 234.95 0)
			(effects
				(font
					(size 1.27 1.27)
					(thickness 0.15)
				)
				(justify left bottom)
				(hide yes)
			)
		)
		(property "Datasheet" ""
			(at 96.52 227.33 0)
			(effects
				(font
					(size 1.27 1.27)
					(thickness 0.15)
				)
				(justify left bottom)
				(hide yes)
			)
		)
		(property "Description" "SMT test point"
			(at 83.82 245.11 0)
			(effects
				(font
					(size 1.27 1.27)
				)
				(hide yes)
			)
		)
		(property "MPN" ""
			(at 95.25 234.315 0)
			(effects
				(font
					(size 1.27 1.27)
					(thickness 0.15)
				)
				(justify left bottom)
				(hide yes)
			)
		)
		(property "Manufacturer" ""
			(at 90.17 234.315 0)
			(effects
				(font
					(size 1.27 1.27)
					(thickness 0.15)
				)
				(justify left bottom)
				(hide yes)
			)
		)
		(property "Author" "Antmicro"
			(at 92.71 234.95 0)
			(effects
				(font
					(size 1.27 1.27)
					(thickness 0.15)
				)
				(justify left bottom)
				(hide yes)
			)
		)
		(property "License" "Apache-2.0"
			(at 95.25 234.95 0)
			(effects
				(font
					(size 1.27 1.27)
					(thickness 0.15)
				)
				(justify left bottom)
				(hide yes)
			)
		)
		(pin "1"
		)
		(instances
			(project "jetson-agx-thor-baseboard"
				(path ""
					(reference "TP118")
					(unit 1)
				)
			)
		)
	)
	(symbol
		(lib_id "antmicropower:+3V3_AON")
		(at 290.83 214.63 0)
		(unit 1)
		(exclude_from_sim no)
		(in_bom yes)
		(on_board yes)
		(dnp no)
		(fields_autoplaced yes)
		(property "Reference" "#PWR0126"
			(at 290.83 218.44 0)
			(effects
				(font
					(size 1.27 1.27)
				)
				(hide yes)
			)
		)
		(property "Value" "+5V_AON"
			(at 290.83 209.55 0)
			(effects
				(font
					(size 1.27 1.27)
				)
			)
		)
		(property "Footprint" ""
			(at 290.83 214.63 0)
			(effects
				(font
					(size 1.27 1.27)
				)
				(hide yes)
			)
		)
		(property "Datasheet" ""
			(at 290.83 214.63 0)
			(effects
				(font
					(size 1.27 1.27)
				)
				(hide yes)
			)
		)
		(property "Description" ""
			(at 290.83 214.63 0)
			(effects
				(font
					(size 1.27 1.27)
				)
				(hide yes)
			)
		)
		(pin "1"
		)
		(instances
			(project "jetson-agx-thor-baseboard"
				(path ""
					(reference "#PWR0126")
					(unit 1)
				)
			)
		)
	)
	(symbol
		(lib_id "antmicroTestPoints:TP_0.75mm_SMD")
		(at 238.76 187.96 0)
		(unit 1)
		(exclude_from_sim no)
		(in_bom no)
		(on_board yes)
		(dnp no)
		(fields_autoplaced yes)
		(property "Reference" "TP120"
			(at 243.84 187.96 0)
			(effects
				(font
					(size 1.27 1.27)
					(thickness 0.15)
				)
				(justify left)
			)
		)
		(property "Value" "TP_0.75mm_SMD"
			(at 248.92 191.77 0)
			(effects
				(font
					(size 1.27 1.27)
					(thickness 0.15)
				)
				(justify left bottom)
				(hide yes)
			)
		)
		(property "Footprint" "antmicro-footprints:TP_SMD_0.75mm"
			(at 248.92 194.31 0)
			(effects
				(font
					(size 1.27 1.27)
					(thickness 0.15)
				)
				(justify left bottom)
				(hide yes)
			)
		)
		(property "Datasheet" ""
			(at 256.54 200.66 0)
			(effects
				(font
					(size 1.27 1.27)
					(thickness 0.15)
				)
				(justify left bottom)
				(hide yes)
			)
		)
		(property "Description" "SMT test point"
			(at 238.76 187.96 0)
			(effects
				(font
					(size 1.27 1.27)
				)
				(hide yes)
			)
		)
		(property "MPN" ""
			(at 249.555 199.39 0)
			(effects
				(font
					(size 1.27 1.27)
					(thickness 0.15)
				)
				(justify left bottom)
				(hide yes)
			)
		)
		(property "Manufacturer" ""
			(at 249.555 194.31 0)
			(effects
				(font
					(size 1.27 1.27)
					(thickness 0.15)
				)
				(justify left bottom)
				(hide yes)
			)
		)
		(property "Author" "Antmicro"
			(at 248.92 196.85 0)
			(effects
				(font
					(size 1.27 1.27)
					(thickness 0.15)
				)
				(justify left bottom)
				(hide yes)
			)
		)
		(property "License" "Apache-2.0"
			(at 248.92 199.39 0)
			(effects
				(font
					(size 1.27 1.27)
					(thickness 0.15)
				)
				(justify left bottom)
				(hide yes)
			)
		)
		(pin "1"
		)
		(instances
			(project "jetson-agx-thor-baseboard"
				(path ""
					(reference "TP120")
					(unit 1)
				)
			)
		)
	)
	(symbol
		(lib_id "antmicropower:GND")
		(at 128.27 259.08 0)
		(unit 1)
		(exclude_from_sim no)
		(in_bom yes)
		(on_board yes)
		(dnp no)
		(property "Reference" "#PWR0581"
			(at 137.16 261.62 0)
			(effects
				(font
					(size 1.27 1.27)
					(thickness 0.15)
				)
				(justify left bottom)
				(hide yes)
			)
		)
		(property "Value" "GND"
			(at 128.27 262.89 0)
			(effects
				(font
					(size 1.27 1.27)
					(thickness 0.15)
				)
			)
		)
		(property "Footprint" ""
			(at 137.16 266.7 0)
			(effects
				(font
					(size 1.27 1.27)
					(thickness 0.15)
				)
				(justify left bottom)
				(hide yes)
			)
		)
		(property "Datasheet" ""
			(at 137.16 271.78 0)
			(effects
				(font
					(size 1.27 1.27)
					(thickness 0.15)
				)
				(justify left bottom)
				(hide yes)
			)
		)
		(property "Description" ""
			(at 128.27 259.08 0)
			(effects
				(font
					(size 1.27 1.27)
				)
				(hide yes)
			)
		)
		(property "Author" "Antmicro"
			(at 137.16 266.7 0)
			(effects
				(font
					(size 1.27 1.27)
					(thickness 0.15)
				)
				(justify left bottom)
				(hide yes)
			)
		)
		(property "License" "Apache-2.0"
			(at 137.16 269.24 0)
			(effects
				(font
					(size 1.27 1.27)
					(thickness 0.15)
				)
				(justify left bottom)
				(hide yes)
			)
		)
		(pin "1"
		)
		(instances
			(project "jetson-agx-thor-baseboard"
				(path ""
					(reference "#PWR0581")
					(unit 1)
				)
			)
		)
	)
	(symbol
		(lib_id "antmicroCapacitors0402:C_10u_0402")
		(at 151.13 48.26 90)
		(unit 1)
		(exclude_from_sim no)
		(in_bom yes)
		(on_board yes)
		(dnp no)
		(fields_autoplaced yes)
		(property "Reference" "C13"
			(at 153.67 44.4436 90)
			(effects
				(font
					(size 1.27 1.27)
					(thickness 0.15)
				)
				(justify right)
			)
		)
		(property "Value" "C_10u_0402"
			(at 161.29 27.94 0)
			(effects
				(font
					(size 1.27 1.27)
					(thickness 0.15)
				)
				(justify left bottom)
				(hide yes)
			)
		)
		(property "Footprint" "antmicro-footprints:C_0402_1005Metric"
			(at 163.83 27.94 0)
			(effects
				(font
					(size 1.27 1.27)
					(thickness 0.15)
				)
				(justify left bottom)
				(hide yes)
			)
		)
		(property "Datasheet" "https://www.yageo.com/en/Chart/Download/pdf/CC0402MRX5R5BB106"
			(at 166.37 27.94 0)
			(effects
				(font
					(size 1.27 1.27)
					(thickness 0.15)
				)
				(justify left bottom)
				(hide yes)
			)
		)
		(property "Description" "SMD Multilayer Ceramic Capacitor, 10 µF, 6.3 V, 0402 [1005 Metric], ± 20%, X5R, CC Series"
			(at 151.13 48.26 0)
			(effects
				(font
					(size 1.27 1.27)
				)
				(hide yes)
			)
		)
		(property "MPN" "CC0402MRX5R5BB106"
			(at 168.91 27.94 0)
			(effects
				(font
					(size 1.27 1.27)
					(thickness 0.15)
				)
				(justify left bottom)
				(hide yes)
			)
		)
		(property "Manufacturer" "YAGEO"
			(at 171.45 27.94 0)
			(effects
				(font
					(size 1.27 1.27)
					(thickness 0.15)
				)
				(justify left bottom)
				(hide yes)
			)
		)
		(property "License" "Apache-2.0"
			(at 173.99 27.94 0)
			(effects
				(font
					(size 1.27 1.27)
					(thickness 0.15)
				)
				(justify left bottom)
				(hide yes)
			)
		)
		(property "Author" "Antmicro"
			(at 176.53 27.94 0)
			(effects
				(font
					(size 1.27 1.27)
					(thickness 0.15)
				)
				(justify left bottom)
				(hide yes)
			)
		)
		(property "Val" "10u"
			(at 153.67 46.9836 90)
			(effects
				(font
					(size 1.27 1.27)
					(thickness 0.15)
				)
				(justify right)
			)
		)
		(property "Voltage" ""
			(at 179.07 27.94 0)
			(effects
				(font
					(size 1.27 1.27)
				)
				(justify left bottom)
				(hide yes)
			)
		)
		(property "Dielectric" "template_dielectric"
			(at 181.61 27.94 0)
			(effects
				(font
					(size 1.27 1.27)
				)
				(justify left bottom)
				(hide yes)
			)
		)
		(pin "1"
		)
		(pin "2"
		)
		(instances
			(project "jetson-agx-thor-baseboard"
				(path ""
					(reference "C13")
					(unit 1)
				)
			)
		)
	)
	(symbol
		(lib_id "antmicropower:GND")
		(at 82.55 41.91 0)
		(unit 1)
		(exclude_from_sim no)
		(in_bom yes)
		(on_board yes)
		(dnp no)
		(property "Reference" "#PWR0519"
			(at 82.55 48.26 0)
			(effects
				(font
					(size 1.27 1.27)
				)
				(justify left bottom)
				(hide yes)
			)
		)
		(property "Value" "GND"
			(at 82.55 45.72 0)
			(effects
				(font
					(size 1.27 1.27)
					(thickness 0.15)
				)
			)
		)
		(property "Footprint" ""
			(at 91.44 49.53 0)
			(effects
				(font
					(size 1.27 1.27)
					(thickness 0.15)
				)
				(justify left bottom)
				(hide yes)
			)
		)
		(property "Datasheet" ""
			(at 91.44 54.61 0)
			(effects
				(font
					(size 1.27 1.27)
					(thickness 0.15)
				)
				(justify left bottom)
				(hide yes)
			)
		)
		(property "Description" ""
			(at 82.55 41.91 0)
			(effects
				(font
					(size 1.27 1.27)
				)
				(hide yes)
			)
		)
		(property "Author" "Antmicro"
			(at 91.44 49.53 0)
			(effects
				(font
					(size 1.27 1.27)
					(thickness 0.15)
				)
				(justify left bottom)
				(hide yes)
			)
		)
		(property "License" "Apache-2.0"
			(at 91.44 52.07 0)
			(effects
				(font
					(size 1.27 1.27)
					(thickness 0.15)
				)
				(justify left bottom)
				(hide yes)
			)
		)
		(pin "1"
		)
		(instances
			(project "jetson-agx-thor-baseboard"
				(path ""
					(reference "#PWR0519")
					(unit 1)
				)
			)
		)
	)
	(symbol
		(lib_id "antmicropower:GND")
		(at 148.59 91.44 0)
		(mirror y)
		(unit 1)
		(exclude_from_sim no)
		(in_bom yes)
		(on_board yes)
		(dnp no)
		(property "Reference" "#PWR036"
			(at 148.59 97.79 0)
			(effects
				(font
					(size 1.27 1.27)
				)
				(justify left bottom)
				(hide yes)
			)
		)
		(property "Value" "GND"
			(at 148.59 95.25 0)
			(effects
				(font
					(size 1.27 1.27)
					(thickness 0.15)
				)
			)
		)
		(property "Footprint" ""
			(at 139.7 99.06 0)
			(effects
				(font
					(size 1.27 1.27)
					(thickness 0.15)
				)
				(justify left bottom)
				(hide yes)
			)
		)
		(property "Datasheet" ""
			(at 139.7 104.14 0)
			(effects
				(font
					(size 1.27 1.27)
					(thickness 0.15)
				)
				(justify left bottom)
				(hide yes)
			)
		)
		(property "Description" ""
			(at 148.59 91.44 0)
			(effects
				(font
					(size 1.27 1.27)
				)
				(hide yes)
			)
		)
		(property "Author" "Antmicro"
			(at 139.7 99.06 0)
			(effects
				(font
					(size 1.27 1.27)
					(thickness 0.15)
				)
				(justify left bottom)
				(hide yes)
			)
		)
		(property "License" "Apache-2.0"
			(at 139.7 101.6 0)
			(effects
				(font
					(size 1.27 1.27)
					(thickness 0.15)
				)
				(justify left bottom)
				(hide yes)
			)
		)
		(pin "1"
		)
		(instances
			(project "jetson-agx-thor-baseboard"
				(path ""
					(reference "#PWR036")
					(unit 1)
				)
			)
		)
	)
	(symbol
		(lib_id "antmicropower:+3V3")
		(at 375.92 201.93 0)
		(unit 1)
		(exclude_from_sim no)
		(in_bom yes)
		(on_board yes)
		(dnp no)
		(property "Reference" "#PWR0140"
			(at 391.16 201.93 0)
			(effects
				(font
					(size 1.27 1.27)
					(thickness 0.15)
				)
				(justify left bottom)
				(hide yes)
			)
		)
		(property "Value" "+3V3"
			(at 375.666 197.866 0)
			(effects
				(font
					(size 1.27 1.27)
					(thickness 0.15)
				)
			)
		)
		(property "Footprint" ""
			(at 391.16 209.55 0)
			(effects
				(font
					(size 1.27 1.27)
					(thickness 0.15)
				)
				(justify left bottom)
				(hide yes)
			)
		)
		(property "Datasheet" ""
			(at 391.16 212.09 0)
			(effects
				(font
					(size 1.27 1.27)
					(thickness 0.15)
				)
				(justify left bottom)
				(hide yes)
			)
		)
		(property "Description" ""
			(at 375.92 201.93 0)
			(effects
				(font
					(size 1.27 1.27)
				)
				(hide yes)
			)
		)
		(property "Author" "Antmicro"
			(at 391.16 204.47 0)
			(effects
				(font
					(size 1.27 1.27)
					(thickness 0.15)
				)
				(justify left bottom)
				(hide yes)
			)
		)
		(property "License" "Apache-2.0"
			(at 391.16 207.01 0)
			(effects
				(font
					(size 1.27 1.27)
					(thickness 0.15)
				)
				(justify left bottom)
				(hide yes)
			)
		)
		(pin "1"
		)
		(instances
			(project "jetson-agx-thor-baseboard"
				(path ""
					(reference "#PWR0140")
					(unit 1)
				)
			)
		)
	)
	(symbol
		(lib_id "antmicroResistors0402:R_470R_0402")
		(at 323.85 162.56 90)
		(unit 1)
		(exclude_from_sim no)
		(in_bom yes)
		(on_board yes)
		(dnp no)
		(property "Reference" "R50"
			(at 324.866 158.75 90)
			(effects
				(font
					(size 1.27 1.27)
					(thickness 0.15)
				)
				(justify right)
			)
		)
		(property "Value" "R_470R_0402"
			(at 336.55 142.24 0)
			(effects
				(font
					(size 1.27 1.27)
					(thickness 0.15)
				)
				(justify left bottom)
				(hide yes)
			)
		)
		(property "Footprint" "antmicro-footprints:R_0402_1005Metric"
			(at 339.09 142.24 0)
			(effects
				(font
					(size 1.27 1.27)
					(thickness 0.15)
				)
				(justify left bottom)
				(hide yes)
			)
		)
		(property "Datasheet" "https://www.bourns.com/docs/product-datasheets/cr.pdf"
			(at 341.63 142.24 0)
			(effects
				(font
					(size 1.27 1.27)
					(thickness 0.15)
				)
				(justify left bottom)
				(hide yes)
			)
		)
		(property "Description" "SMD Chip Resistor, 470 ohm, ± 1%, 62.5 mW, 0402 [1005 Metric], Thick Film, General Purpose"
			(at 323.85 162.56 0)
			(effects
				(font
					(size 1.27 1.27)
				)
				(hide yes)
			)
		)
		(property "MPN" "CR0402-FX-4700GLF"
			(at 344.17 142.24 0)
			(effects
				(font
					(size 1.27 1.27)
					(thickness 0.15)
				)
				(justify left bottom)
				(hide yes)
			)
		)
		(property "Manufacturer" "Bourns"
			(at 346.71 142.24 0)
			(effects
				(font
					(size 1.27 1.27)
					(thickness 0.15)
				)
				(justify left bottom)
				(hide yes)
			)
		)
		(property "License" "Apache-2.0"
			(at 349.25 142.24 0)
			(effects
				(font
					(size 1.27 1.27)
					(thickness 0.15)
				)
				(justify left bottom)
				(hide yes)
			)
		)
		(property "Author" "Antmicro"
			(at 351.79 142.24 0)
			(effects
				(font
					(size 1.27 1.27)
					(thickness 0.15)
				)
				(justify left bottom)
				(hide yes)
			)
		)
		(property "Val" "470R"
			(at 324.866 161.29 90)
			(effects
				(font
					(size 1.27 1.27)
					(thickness 0.15)
				)
				(justify right)
			)
		)
		(property "Tolerance" "1%"
			(at 334.01 142.24 0)
			(effects
				(font
					(size 1.27 1.27)
				)
				(justify left bottom)
				(hide yes)
			)
		)
		(pin "1"
		)
		(pin "2"
		)
		(instances
			(project "jetson-agx-thor-baseboard"
				(path ""
					(reference "R50")
					(unit 1)
				)
			)
		)
	)
	(symbol
		(lib_id "antmicropower:GND")
		(at 227.33 151.13 0)
		(unit 1)
		(exclude_from_sim no)
		(in_bom yes)
		(on_board yes)
		(dnp no)
		(fields_autoplaced yes)
		(property "Reference" "#PWR0610"
			(at 227.33 157.48 0)
			(effects
				(font
					(size 1.27 1.27)
				)
				(justify left bottom)
				(hide yes)
			)
		)
		(property "Value" "GND"
			(at 227.33 154.94 0)
			(effects
				(font
					(size 1.27 1.27)
					(thickness 0.15)
				)
			)
		)
		(property "Footprint" ""
			(at 236.22 158.75 0)
			(effects
				(font
					(size 1.27 1.27)
					(thickness 0.15)
				)
				(justify left bottom)
				(hide yes)
			)
		)
		(property "Datasheet" ""
			(at 236.22 163.83 0)
			(effects
				(font
					(size 1.27 1.27)
					(thickness 0.15)
				)
				(justify left bottom)
				(hide yes)
			)
		)
		(property "Description" ""
			(at 227.33 151.13 0)
			(effects
				(font
					(size 1.27 1.27)
				)
				(hide yes)
			)
		)
		(property "Author" "Antmicro"
			(at 236.22 158.75 0)
			(effects
				(font
					(size 1.27 1.27)
					(thickness 0.15)
				)
				(justify left bottom)
				(hide yes)
			)
		)
		(property "License" "Apache-2.0"
			(at 236.22 161.29 0)
			(effects
				(font
					(size 1.27 1.27)
					(thickness 0.15)
				)
				(justify left bottom)
				(hide yes)
			)
		)
		(pin "1"
		)
		(instances
			(project "jetson-agx-thor-baseboard"
				(path ""
					(reference "#PWR0610")
					(unit 1)
				)
			)
		)
	)
	(symbol
		(lib_id "antmicroCapacitors0402:C_100n_0402")
		(at 179.07 182.88 90)
		(unit 1)
		(exclude_from_sim no)
		(in_bom yes)
		(on_board yes)
		(dnp no)
		(property "Reference" "C223"
			(at 179.07 178.435 90)
			(effects
				(font
					(size 1.27 1.27)
					(thickness 0.15)
				)
				(justify left)
			)
		)
		(property "Value" "C_100n_0402"
			(at 201.93 167.64 0)
			(effects
				(font
					(size 1.27 1.27)
					(thickness 0.15)
				)
				(justify left bottom)
				(hide yes)
			)
		)
		(property "Footprint" "antmicro-footprints:C_0402_1005Metric"
			(at 204.47 167.64 0)
			(effects
				(font
					(size 1.27 1.27)
					(thickness 0.15)
				)
				(justify left bottom)
				(hide yes)
			)
		)
		(property "Datasheet" "https://www.murata.com/products/productdetail?partno=GRM155R61H104KE14%23"
			(at 207.01 167.64 0)
			(effects
				(font
					(size 1.27 1.27)
					(thickness 0.15)
				)
				(justify left bottom)
				(hide yes)
			)
		)
		(property "Description" "SMD Multilayer Ceramic Capacitor, 0.1 µF, 50 V, 0402 [1005 Metric], ± 10%, X5R, GRM Series"
			(at 179.07 182.88 0)
			(effects
				(font
					(size 1.27 1.27)
				)
				(hide yes)
			)
		)
		(property "MPN" "GRM155R61H104KE14D"
			(at 209.55 167.64 0)
			(effects
				(font
					(size 1.27 1.27)
					(thickness 0.15)
				)
				(justify left bottom)
				(hide yes)
			)
		)
		(property "Val" "100n"
			(at 179.07 182.245 90)
			(effects
				(font
					(size 1.27 1.27)
					(thickness 0.15)
				)
				(justify left)
			)
		)
		(property "Voltage" "50V"
			(at 189.23 167.64 0)
			(effects
				(font
					(size 1.27 1.27)
					(thickness 0.15)
				)
				(justify left bottom)
				(hide yes)
			)
		)
		(property "Dielectric" "X5R"
			(at 191.77 167.64 0)
			(effects
				(font
					(size 1.27 1.27)
					(thickness 0.15)
				)
				(justify left bottom)
				(hide yes)
			)
		)
		(property "Manufacturer" "Murata"
			(at 194.31 167.64 0)
			(effects
				(font
					(size 1.27 1.27)
					(thickness 0.15)
				)
				(justify left bottom)
				(hide yes)
			)
		)
		(property "License" "Apache-2.0"
			(at 196.85 167.64 0)
			(effects
				(font
					(size 1.27 1.27)
					(thickness 0.15)
				)
				(justify left bottom)
				(hide yes)
			)
		)
		(property "Author" "Antmicro"
			(at 199.39 167.64 0)
			(effects
				(font
					(size 1.27 1.27)
					(thickness 0.15)
				)
				(justify left bottom)
				(hide yes)
			)
		)
		(pin "1"
		)
		(pin "2"
		)
		(instances
			(project "jetson-agx-thor-baseboard"
				(path ""
					(reference "C223")
					(unit 1)
				)
			)
		)
	)
	(symbol
		(lib_id "antmicropower:GND")
		(at 120.65 259.08 0)
		(unit 1)
		(exclude_from_sim no)
		(in_bom yes)
		(on_board yes)
		(dnp no)
		(property "Reference" "#PWR0580"
			(at 129.54 261.62 0)
			(effects
				(font
					(size 1.27 1.27)
					(thickness 0.15)
				)
				(justify left bottom)
				(hide yes)
			)
		)
		(property "Value" "GND"
			(at 120.65 262.89 0)
			(effects
				(font
					(size 1.27 1.27)
					(thickness 0.15)
				)
			)
		)
		(property "Footprint" ""
			(at 129.54 266.7 0)
			(effects
				(font
					(size 1.27 1.27)
					(thickness 0.15)
				)
				(justify left bottom)
				(hide yes)
			)
		)
		(property "Datasheet" ""
			(at 129.54 271.78 0)
			(effects
				(font
					(size 1.27 1.27)
					(thickness 0.15)
				)
				(justify left bottom)
				(hide yes)
			)
		)
		(property "Description" ""
			(at 120.65 259.08 0)
			(effects
				(font
					(size 1.27 1.27)
				)
				(hide yes)
			)
		)
		(property "Author" "Antmicro"
			(at 129.54 266.7 0)
			(effects
				(font
					(size 1.27 1.27)
					(thickness 0.15)
				)
				(justify left bottom)
				(hide yes)
			)
		)
		(property "License" "Apache-2.0"
			(at 129.54 269.24 0)
			(effects
				(font
					(size 1.27 1.27)
					(thickness 0.15)
				)
				(justify left bottom)
				(hide yes)
			)
		)
		(pin "1"
		)
		(instances
			(project "jetson-agx-thor-baseboard"
				(path ""
					(reference "#PWR0580")
					(unit 1)
				)
			)
		)
	)
	(symbol
		(lib_id "antmicroTVSDiodes:TPD1E0B04_XDFN-2")
		(at 71.12 110.49 270)
		(mirror x)
		(unit 1)
		(exclude_from_sim no)
		(in_bom yes)
		(on_board yes)
		(dnp no)
		(property "Reference" "D5"
			(at 70.866 104.902 90)
			(effects
				(font
					(size 1.27 1.27)
				)
				(justify right)
			)
		)
		(property "Value" "TPD1E0B04_XDFN-2"
			(at 60.96 95.25 0)
			(effects
				(font
					(size 1.27 1.27)
					(thickness 0.15)
				)
				(justify left bottom)
				(hide yes)
			)
		)
		(property "Footprint" "antmicro-footprints:XDFN-2_1x0.60mm"
			(at 66.04 95.25 0)
			(effects
				(font
					(size 1.27 1.27)
					(thickness 0.15)
				)
				(justify left bottom)
				(hide yes)
			)
		)
		(property "Datasheet" "https://www.ti.com/general/docs/suppproductinfo.tsp?distId=26&gotoUrl=https://www.ti.com/lit/gpn/tpd1e0b04"
			(at 63.5 95.25 0)
			(effects
				(font
					(size 1.27 1.27)
					(thickness 0.15)
				)
				(justify left bottom)
				(hide yes)
			)
		)
		(property "Description" "Bidirectional TVS, 8 kV,  XDFN-2, 3.6 V, 0.18 pF"
			(at 71.12 110.49 0)
			(effects
				(font
					(size 1.27 1.27)
				)
				(hide yes)
			)
		)
		(property "Manufacturer" "Texas Instruments"
			(at 58.42 95.25 0)
			(effects
				(font
					(size 1.27 1.27)
					(thickness 0.15)
				)
				(justify left bottom)
				(hide yes)
			)
		)
		(property "MPN" "TPD1E0B04DPYR"
			(at 66.548 101.854 0)
			(effects
				(font
					(size 1.27 1.27)
					(thickness 0.15)
				)
				(justify right)
			)
		)
		(property "Author" "Antmicro"
			(at 55.88 95.25 0)
			(effects
				(font
					(size 1.27 1.27)
					(thickness 0.15)
				)
				(justify left bottom)
				(hide yes)
			)
		)
		(property "License" "Apache-2.0"
			(at 53.34 95.25 0)
			(effects
				(font
					(size 1.27 1.27)
					(thickness 0.15)
				)
				(justify left bottom)
				(hide yes)
			)
		)
		(pin "1"
		)
		(pin "2"
		)
		(instances
			(project "jetson-agx-thor-baseboard"
				(path ""
					(reference "D5")
					(unit 1)
				)
			)
		)
	)
	(symbol
		(lib_id "antmicroResistors0402:R_10k_0402")
		(at 91.44 173.99 270)
		(mirror x)
		(unit 1)
		(exclude_from_sim no)
		(in_bom yes)
		(on_board yes)
		(dnp no)
		(property "Reference" "R24"
			(at 90.17 170.18 90)
			(effects
				(font
					(size 1.27 1.27)
					(thickness 0.15)
				)
				(justify right)
			)
		)
		(property "Value" "R_10k_0402"
			(at 78.74 153.67 0)
			(effects
				(font
					(size 1.27 1.27)
					(thickness 0.15)
				)
				(justify left bottom)
				(hide yes)
			)
		)
		(property "Footprint" "antmicro-footprints:R_0402_1005Metric"
			(at 76.2 153.67 0)
			(effects
				(font
					(size 1.27 1.27)
					(thickness 0.15)
				)
				(justify left bottom)
				(hide yes)
			)
		)
		(property "Datasheet" "https://www.bourns.com/docs/product-datasheets/cr.pdf"
			(at 73.66 153.67 0)
			(effects
				(font
					(size 1.27 1.27)
					(thickness 0.15)
				)
				(justify left bottom)
				(hide yes)
			)
		)
		(property "Description" "SMD Chip Resistor, 10 kohm, ± 1%, 62.5 mW, 0402 [1005 Metric], Thick Film, General Purpose"
			(at 91.44 173.99 0)
			(effects
				(font
					(size 1.27 1.27)
				)
				(hide yes)
			)
		)
		(property "MPN" "CR0402-FX-1002GLF"
			(at 71.12 153.67 0)
			(effects
				(font
					(size 1.27 1.27)
					(thickness 0.15)
				)
				(justify left bottom)
				(hide yes)
			)
		)
		(property "Manufacturer" "Bourns"
			(at 68.58 153.67 0)
			(effects
				(font
					(size 1.27 1.27)
					(thickness 0.15)
				)
				(justify left bottom)
				(hide yes)
			)
		)
		(property "License" "Apache-2.0"
			(at 66.04 153.67 0)
			(effects
				(font
					(size 1.27 1.27)
					(thickness 0.15)
				)
				(justify left bottom)
				(hide yes)
			)
		)
		(property "Author" "Antmicro"
			(at 63.5 153.67 0)
			(effects
				(font
					(size 1.27 1.27)
					(thickness 0.15)
				)
				(justify left bottom)
				(hide yes)
			)
		)
		(property "Val" "10k"
			(at 90.17 172.72 90)
			(effects
				(font
					(size 1.27 1.27)
					(thickness 0.15)
				)
				(justify right)
			)
		)
		(property "Tolerance" "1%"
			(at 81.28 153.67 0)
			(effects
				(font
					(size 1.27 1.27)
				)
				(justify left bottom)
				(hide yes)
			)
		)
		(pin "2"
		)
		(pin "1"
		)
		(instances
			(project "jetson-agx-thor-baseboard"
				(path ""
					(reference "R24")
					(unit 1)
				)
			)
		)
	)
	(symbol
		(lib_id "antmicropower:PWR_FLAG")
		(at 185.42 29.21 0)
		(unit 1)
		(exclude_from_sim no)
		(in_bom yes)
		(on_board yes)
		(dnp no)
		(property "Reference" "#FLG016"
			(at 185.42 27.305 0)
			(effects
				(font
					(size 1.27 1.27)
				)
				(hide yes)
			)
		)
		(property "Value" "PWR_FLAG"
			(at 189.23 24.638 0)
			(effects
				(font
					(size 1.27 1.27)
				)
			)
		)
		(property "Footprint" ""
			(at 185.42 29.21 0)
			(effects
				(font
					(size 1.27 1.27)
				)
				(hide yes)
			)
		)
		(property "Datasheet" ""
			(at 185.42 29.21 0)
			(effects
				(font
					(size 1.27 1.27)
				)
				(hide yes)
			)
		)
		(property "Description" ""
			(at 185.42 29.21 0)
			(effects
				(font
					(size 1.27 1.27)
				)
				(hide yes)
			)
		)
		(pin "1"
		)
		(instances
			(project "jetson-agx-thor-baseboard"
				(path ""
					(reference "#FLG016")
					(unit 1)
				)
			)
		)
	)
	(symbol
		(lib_id "antmicroWire2BoardConnectors:JST_SH_1x4_BM04B-SRSS-TB-LF-SN")
		(at 228.6 139.7 0)
		(unit 1)
		(exclude_from_sim no)
		(in_bom no)
		(on_board yes)
		(dnp yes)
		(property "Reference" "J21"
			(at 230.505 135.89 0)
			(effects
				(font
					(size 1.27 1.27)
					(thickness 0.15)
				)
				(justify left)
			)
		)
		(property "Value" "JST_SH_1x4_BM04B-SRSS-TB-LF-SN"
			(at 248.92 147.32 0)
			(effects
				(font
					(size 1.27 1.27)
					(thickness 0.15)
				)
				(justify left bottom)
				(hide yes)
			)
		)
		(property "Footprint" "antmicro-footprints:Conn_JST_SH_1x4_BM04B-SRSS-TB-LF-SN"
			(at 248.92 149.86 0)
			(effects
				(font
					(size 1.27 1.27)
					(thickness 0.15)
				)
				(justify left bottom)
				(hide yes)
			)
		)
		(property "Datasheet" "https://www.jst-mfg.com/product/pdf/eng/eSH.pdf"
			(at 248.92 152.4 0)
			(effects
				(font
					(size 1.27 1.27)
					(thickness 0.15)
				)
				(justify left bottom)
				(hide yes)
			)
		)
		(property "Description" "Pin Header, Top Entry, Wire-to-Board, 1 mm, 1 Rows, 4 Contacts, Surface Mount, SR"
			(at 248.92 165.1 0)
			(effects
				(font
					(size 1.27 1.27)
				)
				(justify left bottom)
				(hide yes)
			)
		)
		(property "MPN" "BM04B-SRSS-TB(LF)(SN) "
			(at 235.585 156.21 90)
			(effects
				(font
					(size 1.27 1.27)
					(thickness 0.15)
				)
				(justify left)
			)
		)
		(property "Manufacturer" "JST Automotive Connectors"
			(at 248.92 157.48 0)
			(effects
				(font
					(size 1.27 1.27)
					(thickness 0.15)
				)
				(justify left bottom)
				(hide yes)
			)
		)
		(property "Author" "Antmicro"
			(at 248.92 160.02 0)
			(effects
				(font
					(size 1.27 1.27)
					(thickness 0.15)
				)
				(justify left bottom)
				(hide yes)
			)
		)
		(property "License" "Apache-2.0"
			(at 248.92 162.56 0)
			(effects
				(font
					(size 1.27 1.27)
					(thickness 0.15)
				)
				(justify left bottom)
				(hide yes)
			)
		)
		(pin "3"
		)
		(pin "MP"
		)
		(pin "1"
		)
		(pin "4"
		)
		(pin "2"
		)
		(instances
			(project ""
				(path ""
					(reference "J21")
					(unit 1)
				)
			)
		)
	)
	(symbol
		(lib_id "antmicroPushbuttonSwitches:SW_KMR211NGLFS_SMD")
		(at 91.44 201.93 0)
		(unit 1)
		(exclude_from_sim no)
		(in_bom yes)
		(on_board yes)
		(dnp no)
		(property "Reference" "S5"
			(at 100.838 194.31 0)
			(effects
				(font
					(size 1.27 1.27)
				)
				(justify left)
			)
		)
		(property "Value" "SW_KMR211NGLFS_SMD"
			(at 116.84 209.55 0)
			(effects
				(font
					(size 1.27 1.27)
					(thickness 0.15)
				)
				(justify left bottom)
				(hide yes)
			)
		)
		(property "Footprint" "antmicro-footprints:SW_KMR211NGLFS_SMD"
			(at 116.84 212.09 0)
			(effects
				(font
					(size 1.27 1.27)
					(thickness 0.15)
				)
				(justify left bottom)
				(hide yes)
			)
		)
		(property "Datasheet" "http://www.farnell.com/datasheets/2631211.pdf"
			(at 116.84 214.63 0)
			(effects
				(font
					(size 1.27 1.27)
					(thickness 0.15)
				)
				(justify left bottom)
				(hide yes)
			)
		)
		(property "Description" "Tactile Switch, KMR 2 Series, Top Actuated, Surface Mount, Oval Button, 120 gf, 50mA at 32VDC"
			(at 91.44 201.93 0)
			(effects
				(font
					(size 1.27 1.27)
				)
				(hide yes)
			)
		)
		(property "MPN" "KMR211NGLFS"
			(at 89.662 196.85 0)
			(effects
				(font
					(size 1.27 1.27)
					(thickness 0.15)
				)
				(justify left)
			)
		)
		(property "Manufacturer" "C&K"
			(at 116.84 217.17 0)
			(effects
				(font
					(size 1.27 1.27)
					(thickness 0.15)
				)
				(justify left bottom)
				(hide yes)
			)
		)
		(property "Author" "Antmicro"
			(at 116.84 219.71 0)
			(effects
				(font
					(size 1.27 1.27)
					(thickness 0.15)
				)
				(justify left bottom)
				(hide yes)
			)
		)
		(property "License" "Apache-2.0"
			(at 116.84 222.25 0)
			(effects
				(font
					(size 1.27 1.27)
					(thickness 0.15)
				)
				(justify left bottom)
				(hide yes)
			)
		)
		(pin "1"
		)
		(pin "2"
		)
		(pin "3"
		)
		(pin "4"
		)
		(instances
			(project "jetson-agx-thor-baseboard"
				(path ""
					(reference "S5")
					(unit 1)
				)
			)
		)
	)
	(symbol
		(lib_id "antmicropower:VCC")
		(at 156.21 180.34 0)
		(mirror y)
		(unit 1)
		(exclude_from_sim no)
		(in_bom yes)
		(on_board yes)
		(dnp no)
		(property "Reference" "#PWR0538"
			(at 156.21 184.15 0)
			(effects
				(font
					(size 1.27 1.27)
				)
				(hide yes)
			)
		)
		(property "Value" "+5V_SOM"
			(at 151.892 175.514 0)
			(effects
				(font
					(size 1.27 1.27)
				)
				(justify right)
			)
		)
		(property "Footprint" ""
			(at 156.21 180.34 0)
			(effects
				(font
					(size 1.27 1.27)
				)
				(hide yes)
			)
		)
		(property "Datasheet" ""
			(at 156.21 180.34 0)
			(effects
				(font
					(size 1.27 1.27)
				)
				(hide yes)
			)
		)
		(property "Description" ""
			(at 156.21 180.34 0)
			(effects
				(font
					(size 1.27 1.27)
				)
				(hide yes)
			)
		)
		(pin "1"
		)
		(instances
			(project "jetson-agx-thor-baseboard"
				(path ""
					(reference "#PWR0538")
					(unit 1)
				)
			)
		)
	)
	(symbol
		(lib_id "antmicroTransistorsFETsMOSFETsSingle:DMG1012T-7")
		(at 60.96 101.6 0)
		(mirror y)
		(unit 1)
		(exclude_from_sim no)
		(in_bom yes)
		(on_board yes)
		(dnp no)
		(fields_autoplaced yes)
		(property "Reference" "Q2"
			(at 50.8 97.79 0)
			(effects
				(font
					(size 1.27 1.27)
					(thickness 0.15)
				)
				(justify left)
			)
		)
		(property "Value" "DMG1012T-7"
			(at 38.1 106.68 0)
			(effects
				(font
					(size 1.27 1.27)
					(thickness 0.15)
				)
				(justify left bottom)
				(hide yes)
			)
		)
		(property "Footprint" "antmicro-footprints:SOT-523"
			(at 38.1 109.22 0)
			(effects
				(font
					(size 1.27 1.27)
					(thickness 0.15)
				)
				(justify left bottom)
				(hide yes)
			)
		)
		(property "Datasheet" "https://www.diodes.com/assets/Datasheets/ds31783.pdf"
			(at 38.1 111.76 0)
			(effects
				(font
					(size 1.27 1.27)
					(thickness 0.15)
				)
				(justify left bottom)
				(hide yes)
			)
		)
		(property "Description" "Power MOSFET, N Channel, 20 V, 630 mA, 0.3 ohm, SOT-523, Surface Mount"
			(at 1.016 123.444 0)
			(effects
				(font
					(size 1.27 1.27)
				)
				(hide yes)
			)
		)
		(property "MPN" "DMG1012T-7"
			(at 50.8 100.33 0)
			(effects
				(font
					(size 1.27 1.27)
					(thickness 0.15)
				)
				(justify left)
			)
		)
		(property "Manufacturer" "Diodes Incorporated"
			(at 38.1 116.84 0)
			(effects
				(font
					(size 1.27 1.27)
					(thickness 0.15)
				)
				(justify left bottom)
				(hide yes)
			)
		)
		(property "Author" "Antmicro"
			(at 38.1 119.38 0)
			(effects
				(font
					(size 1.27 1.27)
					(thickness 0.15)
				)
				(justify left bottom)
				(hide yes)
			)
		)
		(property "License" "Apache-2.0"
			(at 38.1 121.92 0)
			(effects
				(font
					(size 1.27 1.27)
					(thickness 0.15)
				)
				(justify left bottom)
				(hide yes)
			)
		)
		(pin "2"
		)
		(pin "3"
		)
		(pin "1"
		)
		(instances
			(project "jetson-agx-thor-baseboard"
				(path ""
					(reference "Q2")
					(unit 1)
				)
			)
		)
	)
	(symbol
		(lib_id "antmicroTransistorsFETsMOSFETsSingle:DMG1012T-7")
		(at 384.81 223.52 0)
		(unit 1)
		(exclude_from_sim no)
		(in_bom yes)
		(on_board yes)
		(dnp no)
		(property "Reference" "Q38"
			(at 394.97 226.06 90)
			(effects
				(font
					(size 1.27 1.27)
					(thickness 0.15)
				)
				(justify left)
			)
		)
		(property "Value" "DMG1012T-7"
			(at 407.67 240.03 0)
			(effects
				(font
					(size 1.27 1.27)
					(thickness 0.15)
				)
				(justify left bottom)
				(hide yes)
			)
		)
		(property "Footprint" "antmicro-footprints:SOT-523"
			(at 407.67 234.95 0)
			(effects
				(font
					(size 1.27 1.27)
					(thickness 0.15)
				)
				(justify left bottom)
				(hide yes)
			)
		)
		(property "Datasheet" "https://www.diodes.com/assets/Datasheets/ds31783.pdf"
			(at 407.67 237.49 0)
			(effects
				(font
					(size 1.27 1.27)
					(thickness 0.15)
				)
				(justify left bottom)
				(hide yes)
			)
		)
		(property "Description" "Power MOSFET, N Channel, 20 V, 630 mA, 0.3 ohm, SOT-523, Surface Mount"
			(at 443.992 249.428 0)
			(effects
				(font
					(size 1.27 1.27)
				)
				(hide yes)
			)
		)
		(property "MPN" "DMG1012T-7"
			(at 397.51 226.06 90)
			(effects
				(font
					(size 1.27 1.27)
					(thickness 0.15)
				)
				(justify left)
			)
		)
		(property "Manufacturer" "Diodes Incorporated"
			(at 407.67 242.57 0)
			(effects
				(font
					(size 1.27 1.27)
					(thickness 0.15)
				)
				(justify left bottom)
				(hide yes)
			)
		)
		(property "Author" "Antmicro"
			(at 407.67 245.11 0)
			(effects
				(font
					(size 1.27 1.27)
					(thickness 0.15)
				)
				(justify left bottom)
				(hide yes)
			)
		)
		(property "License" "Apache-2.0"
			(at 407.67 247.65 0)
			(effects
				(font
					(size 1.27 1.27)
					(thickness 0.15)
				)
				(justify left bottom)
				(hide yes)
			)
		)
		(pin "1"
		)
		(pin "3"
		)
		(pin "2"
		)
		(instances
			(project "jetson-agx-thor-baseboard"
				(path ""
					(reference "Q38")
					(unit 1)
				)
			)
		)
	)
	(symbol
		(lib_id "antmicroTestPoints:TP_0.75mm_SMD")
		(at 251.46 91.44 0)
		(unit 1)
		(exclude_from_sim no)
		(in_bom no)
		(on_board yes)
		(dnp no)
		(fields_autoplaced yes)
		(property "Reference" "TP51"
			(at 256.54 91.44 0)
			(effects
				(font
					(size 1.27 1.27)
					(thickness 0.15)
				)
				(justify left)
			)
		)
		(property "Value" "TP_0.75mm_SMD"
			(at 261.62 95.25 0)
			(effects
				(font
					(size 1.27 1.27)
					(thickness 0.15)
				)
				(justify left bottom)
				(hide yes)
			)
		)
		(property "Footprint" "antmicro-footprints:TP_SMD_0.75mm"
			(at 261.62 97.79 0)
			(effects
				(font
					(size 1.27 1.27)
					(thickness 0.15)
				)
				(justify left bottom)
				(hide yes)
			)
		)
		(property "Datasheet" ""
			(at 269.24 104.14 0)
			(effects
				(font
					(size 1.27 1.27)
					(thickness 0.15)
				)
				(justify left bottom)
				(hide yes)
			)
		)
		(property "Description" "SMT test point"
			(at 251.46 91.44 0)
			(effects
				(font
					(size 1.27 1.27)
				)
				(hide yes)
			)
		)
		(property "MPN" ""
			(at 262.255 102.87 0)
			(effects
				(font
					(size 1.27 1.27)
					(thickness 0.15)
				)
				(justify left bottom)
				(hide yes)
			)
		)
		(property "Manufacturer" ""
			(at 262.255 97.79 0)
			(effects
				(font
					(size 1.27 1.27)
					(thickness 0.15)
				)
				(justify left bottom)
				(hide yes)
			)
		)
		(property "Author" "Antmicro"
			(at 261.62 100.33 0)
			(effects
				(font
					(size 1.27 1.27)
					(thickness 0.15)
				)
				(justify left bottom)
				(hide yes)
			)
		)
		(property "License" "Apache-2.0"
			(at 261.62 102.87 0)
			(effects
				(font
					(size 1.27 1.27)
					(thickness 0.15)
				)
				(justify left bottom)
				(hide yes)
			)
		)
		(pin "1"
		)
		(instances
			(project "jetson-agx-thor-baseboard"
				(path ""
					(reference "TP51")
					(unit 1)
				)
			)
		)
	)
	(symbol
		(lib_id "antmicroResistors0402:R_470R_0402")
		(at 391.16 208.28 90)
		(unit 1)
		(exclude_from_sim no)
		(in_bom yes)
		(on_board yes)
		(dnp no)
		(property "Reference" "R60"
			(at 392.176 204.47 90)
			(effects
				(font
					(size 1.27 1.27)
					(thickness 0.15)
				)
				(justify right)
			)
		)
		(property "Value" "R_470R_0402"
			(at 403.86 187.96 0)
			(effects
				(font
					(size 1.27 1.27)
					(thickness 0.15)
				)
				(justify left bottom)
				(hide yes)
			)
		)
		(property "Footprint" "antmicro-footprints:R_0402_1005Metric"
			(at 406.4 187.96 0)
			(effects
				(font
					(size 1.27 1.27)
					(thickness 0.15)
				)
				(justify left bottom)
				(hide yes)
			)
		)
		(property "Datasheet" "https://www.bourns.com/docs/product-datasheets/cr.pdf"
			(at 408.94 187.96 0)
			(effects
				(font
					(size 1.27 1.27)
					(thickness 0.15)
				)
				(justify left bottom)
				(hide yes)
			)
		)
		(property "Description" "SMD Chip Resistor, 470 ohm, ± 1%, 62.5 mW, 0402 [1005 Metric], Thick Film, General Purpose"
			(at 391.16 208.28 0)
			(effects
				(font
					(size 1.27 1.27)
				)
				(hide yes)
			)
		)
		(property "MPN" "CR0402-FX-4700GLF"
			(at 411.48 187.96 0)
			(effects
				(font
					(size 1.27 1.27)
					(thickness 0.15)
				)
				(justify left bottom)
				(hide yes)
			)
		)
		(property "Manufacturer" "Bourns"
			(at 414.02 187.96 0)
			(effects
				(font
					(size 1.27 1.27)
					(thickness 0.15)
				)
				(justify left bottom)
				(hide yes)
			)
		)
		(property "License" "Apache-2.0"
			(at 416.56 187.96 0)
			(effects
				(font
					(size 1.27 1.27)
					(thickness 0.15)
				)
				(justify left bottom)
				(hide yes)
			)
		)
		(property "Author" "Antmicro"
			(at 419.1 187.96 0)
			(effects
				(font
					(size 1.27 1.27)
					(thickness 0.15)
				)
				(justify left bottom)
				(hide yes)
			)
		)
		(property "Val" "470R"
			(at 392.176 207.01 90)
			(effects
				(font
					(size 1.27 1.27)
					(thickness 0.15)
				)
				(justify right)
			)
		)
		(property "Tolerance" "1%"
			(at 401.32 187.96 0)
			(effects
				(font
					(size 1.27 1.27)
				)
				(justify left bottom)
				(hide yes)
			)
		)
		(pin "1"
		)
		(pin "2"
		)
		(instances
			(project "jetson-agx-thor-baseboard"
				(path ""
					(reference "R60")
					(unit 1)
				)
			)
		)
	)
	(symbol
		(lib_id "antmicropower:+3V3_AON")
		(at 132.08 69.85 0)
		(unit 1)
		(exclude_from_sim no)
		(in_bom yes)
		(on_board yes)
		(dnp no)
		(fields_autoplaced yes)
		(property "Reference" "#PWR033"
			(at 132.08 73.66 0)
			(effects
				(font
					(size 1.27 1.27)
				)
				(hide yes)
			)
		)
		(property "Value" "+3V3_AON"
			(at 132.08 64.77 0)
			(effects
				(font
					(size 1.27 1.27)
				)
			)
		)
		(property "Footprint" ""
			(at 132.08 69.85 0)
			(effects
				(font
					(size 1.27 1.27)
				)
				(hide yes)
			)
		)
		(property "Datasheet" ""
			(at 132.08 69.85 0)
			(effects
				(font
					(size 1.27 1.27)
				)
				(hide yes)
			)
		)
		(property "Description" ""
			(at 132.08 69.85 0)
			(effects
				(font
					(size 1.27 1.27)
				)
				(hide yes)
			)
		)
		(pin "1"
		)
		(instances
			(project "jetson-agx-thor-baseboard"
				(path ""
					(reference "#PWR033")
					(unit 1)
				)
			)
		)
	)
	(symbol
		(lib_id "antmicroCapacitors0402:C_10u_0402")
		(at 142.24 48.26 90)
		(unit 1)
		(exclude_from_sim no)
		(in_bom yes)
		(on_board yes)
		(dnp no)
		(fields_autoplaced yes)
		(property "Reference" "C12"
			(at 144.78 44.4436 90)
			(effects
				(font
					(size 1.27 1.27)
					(thickness 0.15)
				)
				(justify right)
			)
		)
		(property "Value" "C_10u_0402"
			(at 152.4 27.94 0)
			(effects
				(font
					(size 1.27 1.27)
					(thickness 0.15)
				)
				(justify left bottom)
				(hide yes)
			)
		)
		(property "Footprint" "antmicro-footprints:C_0402_1005Metric"
			(at 154.94 27.94 0)
			(effects
				(font
					(size 1.27 1.27)
					(thickness 0.15)
				)
				(justify left bottom)
				(hide yes)
			)
		)
		(property "Datasheet" "https://www.yageo.com/en/Chart/Download/pdf/CC0402MRX5R5BB106"
			(at 157.48 27.94 0)
			(effects
				(font
					(size 1.27 1.27)
					(thickness 0.15)
				)
				(justify left bottom)
				(hide yes)
			)
		)
		(property "Description" "SMD Multilayer Ceramic Capacitor, 10 µF, 6.3 V, 0402 [1005 Metric], ± 20%, X5R, CC Series"
			(at 142.24 48.26 0)
			(effects
				(font
					(size 1.27 1.27)
				)
				(hide yes)
			)
		)
		(property "MPN" "CC0402MRX5R5BB106"
			(at 160.02 27.94 0)
			(effects
				(font
					(size 1.27 1.27)
					(thickness 0.15)
				)
				(justify left bottom)
				(hide yes)
			)
		)
		(property "Manufacturer" "YAGEO"
			(at 162.56 27.94 0)
			(effects
				(font
					(size 1.27 1.27)
					(thickness 0.15)
				)
				(justify left bottom)
				(hide yes)
			)
		)
		(property "License" "Apache-2.0"
			(at 165.1 27.94 0)
			(effects
				(font
					(size 1.27 1.27)
					(thickness 0.15)
				)
				(justify left bottom)
				(hide yes)
			)
		)
		(property "Author" "Antmicro"
			(at 167.64 27.94 0)
			(effects
				(font
					(size 1.27 1.27)
					(thickness 0.15)
				)
				(justify left bottom)
				(hide yes)
			)
		)
		(property "Val" "10u"
			(at 144.78 46.9836 90)
			(effects
				(font
					(size 1.27 1.27)
					(thickness 0.15)
				)
				(justify right)
			)
		)
		(property "Voltage" ""
			(at 170.18 27.94 0)
			(effects
				(font
					(size 1.27 1.27)
				)
				(justify left bottom)
				(hide yes)
			)
		)
		(property "Dielectric" "template_dielectric"
			(at 172.72 27.94 0)
			(effects
				(font
					(size 1.27 1.27)
				)
				(justify left bottom)
				(hide yes)
			)
		)
		(pin "1"
		)
		(pin "2"
		)
		(instances
			(project "jetson-agx-thor-baseboard"
				(path ""
					(reference "C12")
					(unit 1)
				)
			)
		)
	)
	(symbol
		(lib_id "antmicroTestPoints:TP_0.75mm_SMD")
		(at 251.46 100.33 0)
		(unit 1)
		(exclude_from_sim no)
		(in_bom no)
		(on_board yes)
		(dnp no)
		(fields_autoplaced yes)
		(property "Reference" "TP53"
			(at 256.54 100.33 0)
			(effects
				(font
					(size 1.27 1.27)
					(thickness 0.15)
				)
				(justify left)
			)
		)
		(property "Value" "TP_0.75mm_SMD"
			(at 261.62 104.14 0)
			(effects
				(font
					(size 1.27 1.27)
					(thickness 0.15)
				)
				(justify left bottom)
				(hide yes)
			)
		)
		(property "Footprint" "antmicro-footprints:TP_SMD_0.75mm"
			(at 261.62 106.68 0)
			(effects
				(font
					(size 1.27 1.27)
					(thickness 0.15)
				)
				(justify left bottom)
				(hide yes)
			)
		)
		(property "Datasheet" ""
			(at 269.24 113.03 0)
			(effects
				(font
					(size 1.27 1.27)
					(thickness 0.15)
				)
				(justify left bottom)
				(hide yes)
			)
		)
		(property "Description" "SMT test point"
			(at 251.46 100.33 0)
			(effects
				(font
					(size 1.27 1.27)
				)
				(hide yes)
			)
		)
		(property "MPN" ""
			(at 262.255 111.76 0)
			(effects
				(font
					(size 1.27 1.27)
					(thickness 0.15)
				)
				(justify left bottom)
				(hide yes)
			)
		)
		(property "Manufacturer" ""
			(at 262.255 106.68 0)
			(effects
				(font
					(size 1.27 1.27)
					(thickness 0.15)
				)
				(justify left bottom)
				(hide yes)
			)
		)
		(property "Author" "Antmicro"
			(at 261.62 109.22 0)
			(effects
				(font
					(size 1.27 1.27)
					(thickness 0.15)
				)
				(justify left bottom)
				(hide yes)
			)
		)
		(property "License" "Apache-2.0"
			(at 261.62 111.76 0)
			(effects
				(font
					(size 1.27 1.27)
					(thickness 0.15)
				)
				(justify left bottom)
				(hide yes)
			)
		)
		(pin "1"
		)
		(instances
			(project "jetson-agx-thor-baseboard"
				(path ""
					(reference "TP53")
					(unit 1)
				)
			)
		)
	)
	(symbol
		(lib_id "antmicropower:+3V3_AON")
		(at 236.22 177.8 0)
		(unit 1)
		(exclude_from_sim no)
		(in_bom yes)
		(on_board yes)
		(dnp no)
		(fields_autoplaced yes)
		(property "Reference" "#PWR0569"
			(at 236.22 181.61 0)
			(effects
				(font
					(size 1.27 1.27)
				)
				(hide yes)
			)
		)
		(property "Value" "+3V3_AON"
			(at 236.22 172.72 0)
			(effects
				(font
					(size 1.27 1.27)
				)
			)
		)
		(property "Footprint" ""
			(at 236.22 177.8 0)
			(effects
				(font
					(size 1.27 1.27)
				)
				(hide yes)
			)
		)
		(property "Datasheet" ""
			(at 236.22 177.8 0)
			(effects
				(font
					(size 1.27 1.27)
				)
				(hide yes)
			)
		)
		(property "Description" ""
			(at 236.22 177.8 0)
			(effects
				(font
					(size 1.27 1.27)
				)
				(hide yes)
			)
		)
		(pin "1"
		)
		(instances
			(project "jetson-agx-thor-baseboard"
				(path ""
					(reference "#PWR0569")
					(unit 1)
				)
			)
		)
	)
	(symbol
		(lib_id "antmicroClockTimingProgrammableTimersandOscillators:LTC6994CDCB-1_DFN")
		(at 167.64 236.22 0)
		(unit 1)
		(exclude_from_sim no)
		(in_bom yes)
		(on_board yes)
		(dnp no)
		(property "Reference" "U3"
			(at 170.18 233.172 0)
			(effects
				(font
					(size 1.27 1.27)
					(thickness 0.15)
				)
				(justify left bottom)
			)
		)
		(property "Value" "LTC6994CDCB-1_DFN"
			(at 167.386 248.92 0)
			(effects
				(font
					(size 1.27 1.27)
					(thickness 0.15)
				)
				(justify left bottom)
				(hide yes)
			)
		)
		(property "Footprint" "antmicro-footprints:DFN-6-1EP_3x2mm_P0.5mm_EP1.65x1.35mm"
			(at 167.386 251.46 0)
			(effects
				(font
					(size 1.27 1.27)
					(thickness 0.15)
				)
				(justify left bottom)
				(hide yes)
			)
		)
		(property "Datasheet" "https://www.analog.com/media/en/technical-documentation/data-sheets/699412fb.pdf"
			(at 167.386 254 0)
			(effects
				(font
					(size 1.27 1.27)
					(thickness 0.15)
				)
				(justify left bottom)
				(hide yes)
			)
		)
		(property "Description" "Programmable delay block"
			(at 167.386 264.16 0)
			(effects
				(font
					(size 1.27 1.27)
				)
				(justify left bottom)
				(hide yes)
			)
		)
		(property "MPN" "LTC6994CDCB-1#TRMPBF"
			(at 176.53 248.92 0)
			(effects
				(font
					(size 1.27 1.27)
					(thickness 0.15)
				)
				(justify bottom)
			)
		)
		(property "Manufacturer" "Analog Devices"
			(at 167.386 256.54 0)
			(effects
				(font
					(size 1.27 1.27)
					(thickness 0.15)
				)
				(justify left bottom)
				(hide yes)
			)
		)
		(property "Author" "Antmicro"
			(at 167.386 259.08 0)
			(effects
				(font
					(size 1.27 1.27)
					(thickness 0.15)
				)
				(justify left bottom)
				(hide yes)
			)
		)
		(property "License" "Apache-2.0"
			(at 167.386 261.62 0)
			(effects
				(font
					(size 1.27 1.27)
					(thickness 0.15)
				)
				(justify left bottom)
				(hide yes)
			)
		)
		(pin "6"
		)
		(pin "4"
		)
		(pin "3"
		)
		(pin "5"
		)
		(pin "2"
		)
		(pin "1"
		)
		(pin "7"
		)
		(instances
			(project ""
				(path ""
					(reference "U3")
					(unit 1)
				)
			)
		)
	)
	(symbol
		(lib_id "antmicroCapacitors0402:C_100n_0402")
		(at 160.02 38.1 90)
		(unit 1)
		(exclude_from_sim no)
		(in_bom yes)
		(on_board yes)
		(dnp no)
		(fields_autoplaced yes)
		(property "Reference" "C17"
			(at 162.56 34.2836 90)
			(effects
				(font
					(size 1.27 1.27)
					(thickness 0.15)
				)
				(justify right)
			)
		)
		(property "Value" "C_100n_0402"
			(at 182.88 22.86 0)
			(effects
				(font
					(size 1.27 1.27)
					(thickness 0.15)
				)
				(justify left bottom)
				(hide yes)
			)
		)
		(property "Footprint" "antmicro-footprints:C_0402_1005Metric"
			(at 185.42 22.86 0)
			(effects
				(font
					(size 1.27 1.27)
					(thickness 0.15)
				)
				(justify left bottom)
				(hide yes)
			)
		)
		(property "Datasheet" "https://www.murata.com/products/productdetail?partno=GRM155R61H104KE14%23"
			(at 187.96 22.86 0)
			(effects
				(font
					(size 1.27 1.27)
					(thickness 0.15)
				)
				(justify left bottom)
				(hide yes)
			)
		)
		(property "Description" "SMD Multilayer Ceramic Capacitor, 0.1 µF, 50 V, 0402 [1005 Metric], ± 10%, X5R, GRM Series"
			(at 160.02 38.1 0)
			(effects
				(font
					(size 1.27 1.27)
				)
				(hide yes)
			)
		)
		(property "MPN" "GRM155R61H104KE14D"
			(at 190.5 22.86 0)
			(effects
				(font
					(size 1.27 1.27)
					(thickness 0.15)
				)
				(justify left bottom)
				(hide yes)
			)
		)
		(property "Val" "100n"
			(at 162.56 36.8236 90)
			(effects
				(font
					(size 1.27 1.27)
					(thickness 0.15)
				)
				(justify right)
			)
		)
		(property "Voltage" "50V"
			(at 170.18 22.86 0)
			(effects
				(font
					(size 1.27 1.27)
					(thickness 0.15)
				)
				(justify left bottom)
				(hide yes)
			)
		)
		(property "Dielectric" "X5R"
			(at 172.72 22.86 0)
			(effects
				(font
					(size 1.27 1.27)
					(thickness 0.15)
				)
				(justify left bottom)
				(hide yes)
			)
		)
		(property "Manufacturer" "Murata"
			(at 175.26 22.86 0)
			(effects
				(font
					(size 1.27 1.27)
					(thickness 0.15)
				)
				(justify left bottom)
				(hide yes)
			)
		)
		(property "License" "Apache-2.0"
			(at 177.8 22.86 0)
			(effects
				(font
					(size 1.27 1.27)
					(thickness 0.15)
				)
				(justify left bottom)
				(hide yes)
			)
		)
		(property "Author" "Antmicro"
			(at 180.34 22.86 0)
			(effects
				(font
					(size 1.27 1.27)
					(thickness 0.15)
				)
				(justify left bottom)
				(hide yes)
			)
		)
		(pin "1"
		)
		(pin "2"
		)
		(instances
			(project "jetson-agx-thor-baseboard"
				(path ""
					(reference "C17")
					(unit 1)
				)
			)
		)
	)
	(symbol
		(lib_id "antmicroCapacitors0603:C_22u_16V_0603")
		(at 151.13 38.1 90)
		(unit 1)
		(exclude_from_sim no)
		(in_bom yes)
		(on_board yes)
		(dnp no)
		(property "Reference" "C24"
			(at 153.67 34.2836 90)
			(effects
				(font
					(size 1.27 1.27)
					(thickness 0.15)
				)
				(justify right)
			)
		)
		(property "Value" "C_22u_16V_0603"
			(at 161.29 17.78 0)
			(effects
				(font
					(size 1.27 1.27)
					(thickness 0.15)
				)
				(justify left bottom)
				(hide yes)
			)
		)
		(property "Footprint" "antmicro-footprints:C_0603_1608Metric_EIA"
			(at 163.83 17.78 0)
			(effects
				(font
					(size 1.27 1.27)
					(thickness 0.15)
				)
				(justify left bottom)
				(hide yes)
			)
		)
		(property "Datasheet" "https://product.samsungsem.com/mlcc/CL10A226MO7JZN.do"
			(at 166.37 17.78 0)
			(effects
				(font
					(size 1.27 1.27)
					(thickness 0.15)
				)
				(justify left bottom)
				(hide yes)
			)
		)
		(property "Description" "SMD Multilayer Ceramic Capacitor"
			(at 151.13 38.1 0)
			(effects
				(font
					(size 1.27 1.27)
				)
				(hide yes)
			)
		)
		(property "MPN" "CL10A226MO7JZNC"
			(at 168.91 17.78 0)
			(effects
				(font
					(size 1.27 1.27)
					(thickness 0.15)
				)
				(justify left bottom)
				(hide yes)
			)
		)
		(property "Manufacturer" "Samsung Electro-Mechanics"
			(at 171.45 17.78 0)
			(effects
				(font
					(size 1.27 1.27)
					(thickness 0.15)
				)
				(justify left bottom)
				(hide yes)
			)
		)
		(property "License" "Apache-2.0"
			(at 173.99 17.78 0)
			(effects
				(font
					(size 1.27 1.27)
					(thickness 0.15)
				)
				(justify left bottom)
				(hide yes)
			)
		)
		(property "Author" "Antmicro"
			(at 176.53 17.78 0)
			(effects
				(font
					(size 1.27 1.27)
					(thickness 0.15)
				)
				(justify left bottom)
				(hide yes)
			)
		)
		(property "Val" "22u"
			(at 153.67 36.8236 90)
			(effects
				(font
					(size 1.27 1.27)
					(thickness 0.15)
				)
				(justify right)
			)
		)
		(property "Voltage" "16V"
			(at 179.07 17.78 0)
			(effects
				(font
					(size 1.27 1.27)
				)
				(justify left bottom)
				(hide yes)
			)
		)
		(property "Dielectric" "X7R"
			(at 181.61 17.78 0)
			(effects
				(font
					(size 1.27 1.27)
				)
				(justify left bottom)
				(hide yes)
			)
		)
		(property "Public" "False"
			(at 184.15 17.78 0)
			(effects
				(font
					(size 1.27 1.27)
				)
				(justify left bottom)
				(hide yes)
			)
		)
		(pin "1"
		)
		(pin "2"
		)
		(instances
			(project "jetson-agx-thor-baseboard"
				(path ""
					(reference "C24")
					(unit 1)
				)
			)
		)
	)
	(symbol
		(lib_id "antmicroResistorsmisc:R_220R_1206")
		(at 307.34 162.56 90)
		(unit 1)
		(exclude_from_sim no)
		(in_bom yes)
		(on_board yes)
		(dnp no)
		(property "Reference" "R102"
			(at 308.61 158.75 90)
			(effects
				(font
					(size 1.27 1.27)
					(thickness 0.15)
				)
				(justify right)
			)
		)
		(property "Value" "R_220R_1206"
			(at 320.04 142.24 0)
			(effects
				(font
					(size 1.27 1.27)
					(thickness 0.15)
				)
				(justify left bottom)
				(hide yes)
			)
		)
		(property "Footprint" "antmicro-footprints:R_1206_3216Metric"
			(at 322.58 142.24 0)
			(effects
				(font
					(size 1.27 1.27)
					(thickness 0.15)
				)
				(justify left bottom)
				(hide yes)
			)
		)
		(property "Datasheet" "https://www.bourns.com/docs/product-datasheets/cr.pdf"
			(at 325.12 142.24 0)
			(effects
				(font
					(size 1.27 1.27)
					(thickness 0.15)
				)
				(justify left bottom)
				(hide yes)
			)
		)
		(property "Description" "SMT Chip Resistor, 220 ohm, ± 1%, 250 mW, 1206 [3216 Metric]"
			(at 337.82 142.24 0)
			(effects
				(font
					(size 1.27 1.27)
				)
				(justify left bottom)
				(hide yes)
			)
		)
		(property "MPN" "CR1206-FX-2200ELF"
			(at 327.66 142.24 0)
			(effects
				(font
					(size 1.27 1.27)
					(thickness 0.15)
				)
				(justify left bottom)
				(hide yes)
			)
		)
		(property "Manufacturer" "Bourns"
			(at 330.2 142.24 0)
			(effects
				(font
					(size 1.27 1.27)
					(thickness 0.15)
				)
				(justify left bottom)
				(hide yes)
			)
		)
		(property "License" "Apache-2.0"
			(at 332.74 142.24 0)
			(effects
				(font
					(size 1.27 1.27)
					(thickness 0.15)
				)
				(justify left bottom)
				(hide yes)
			)
		)
		(property "Author" "Antmicro"
			(at 335.28 142.24 0)
			(effects
				(font
					(size 1.27 1.27)
					(thickness 0.15)
				)
				(justify left bottom)
				(hide yes)
			)
		)
		(property "Val" "220R"
			(at 308.61 161.29 90)
			(effects
				(font
					(size 1.27 1.27)
					(thickness 0.15)
				)
				(justify right)
			)
		)
		(property "Tolerance" "1%"
			(at 317.5 142.24 0)
			(effects
				(font
					(size 1.27 1.27)
				)
				(justify left bottom)
				(hide yes)
			)
		)
		(pin "1"
		)
		(pin "2"
		)
		(instances
			(project ""
				(path ""
					(reference "R102")
					(unit 1)
				)
			)
		)
	)
	(symbol
		(lib_id "antmicropower:GND")
		(at 363.22 88.9 0)
		(unit 1)
		(exclude_from_sim no)
		(in_bom yes)
		(on_board yes)
		(dnp no)
		(property "Reference" "#PWR0453"
			(at 363.22 95.25 0)
			(effects
				(font
					(size 1.27 1.27)
				)
				(justify left bottom)
				(hide yes)
			)
		)
		(property "Value" "GND"
			(at 363.22 92.71 0)
			(effects
				(font
					(size 1.27 1.27)
					(thickness 0.15)
				)
			)
		)
		(property "Footprint" ""
			(at 372.11 96.52 0)
			(effects
				(font
					(size 1.27 1.27)
					(thickness 0.15)
				)
				(justify left bottom)
				(hide yes)
			)
		)
		(property "Datasheet" ""
			(at 372.11 101.6 0)
			(effects
				(font
					(size 1.27 1.27)
					(thickness 0.15)
				)
				(justify left bottom)
				(hide yes)
			)
		)
		(property "Description" ""
			(at 363.22 88.9 0)
			(effects
				(font
					(size 1.27 1.27)
				)
				(hide yes)
			)
		)
		(property "Author" "Antmicro"
			(at 372.11 96.52 0)
			(effects
				(font
					(size 1.27 1.27)
					(thickness 0.15)
				)
				(justify left bottom)
				(hide yes)
			)
		)
		(property "License" "Apache-2.0"
			(at 372.11 99.06 0)
			(effects
				(font
					(size 1.27 1.27)
					(thickness 0.15)
				)
				(justify left bottom)
				(hide yes)
			)
		)
		(pin "1"
		)
		(instances
			(project "jetson-agx-thor-baseboard"
				(path ""
					(reference "#PWR0453")
					(unit 1)
				)
			)
		)
	)
	(symbol
		(lib_id "antmicropower:+3V3_AON")
		(at 203.2 266.7 0)
		(unit 1)
		(exclude_from_sim no)
		(in_bom yes)
		(on_board yes)
		(dnp no)
		(fields_autoplaced yes)
		(property "Reference" "#PWR0116"
			(at 203.2 270.51 0)
			(effects
				(font
					(size 1.27 1.27)
				)
				(hide yes)
			)
		)
		(property "Value" "+5V_AON"
			(at 203.2 261.62 0)
			(effects
				(font
					(size 1.27 1.27)
				)
			)
		)
		(property "Footprint" ""
			(at 203.2 266.7 0)
			(effects
				(font
					(size 1.27 1.27)
				)
				(hide yes)
			)
		)
		(property "Datasheet" ""
			(at 203.2 266.7 0)
			(effects
				(font
					(size 1.27 1.27)
				)
				(hide yes)
			)
		)
		(property "Description" ""
			(at 203.2 266.7 0)
			(effects
				(font
					(size 1.27 1.27)
				)
				(hide yes)
			)
		)
		(pin "1"
		)
		(instances
			(project "jetson-agx-thor-baseboard"
				(path ""
					(reference "#PWR0116")
					(unit 1)
				)
			)
		)
	)
	(symbol
		(lib_id "antmicropower:GND")
		(at 91.44 182.88 0)
		(unit 1)
		(exclude_from_sim no)
		(in_bom yes)
		(on_board yes)
		(dnp no)
		(property "Reference" "#PWR0766"
			(at 100.33 185.42 0)
			(effects
				(font
					(size 1.27 1.27)
					(thickness 0.15)
				)
				(justify left bottom)
				(hide yes)
			)
		)
		(property "Value" "GND"
			(at 91.44 186.69 0)
			(effects
				(font
					(size 1.27 1.27)
					(thickness 0.15)
				)
			)
		)
		(property "Footprint" ""
			(at 100.33 190.5 0)
			(effects
				(font
					(size 1.27 1.27)
					(thickness 0.15)
				)
				(justify left bottom)
				(hide yes)
			)
		)
		(property "Datasheet" ""
			(at 100.33 195.58 0)
			(effects
				(font
					(size 1.27 1.27)
					(thickness 0.15)
				)
				(justify left bottom)
				(hide yes)
			)
		)
		(property "Description" ""
			(at 91.44 182.88 0)
			(effects
				(font
					(size 1.27 1.27)
				)
				(hide yes)
			)
		)
		(property "Author" "Antmicro"
			(at 100.33 190.5 0)
			(effects
				(font
					(size 1.27 1.27)
					(thickness 0.15)
				)
				(justify left bottom)
				(hide yes)
			)
		)
		(property "License" "Apache-2.0"
			(at 100.33 193.04 0)
			(effects
				(font
					(size 1.27 1.27)
					(thickness 0.15)
				)
				(justify left bottom)
				(hide yes)
			)
		)
		(pin "1"
		)
		(instances
			(project "jetson-agx-thor-baseboard"
				(path ""
					(reference "#PWR0766")
					(unit 1)
				)
			)
		)
	)
	(symbol
		(lib_id "antmicropower:GND")
		(at 375.92 62.23 0)
		(unit 1)
		(exclude_from_sim no)
		(in_bom yes)
		(on_board yes)
		(dnp no)
		(property "Reference" "#PWR027"
			(at 384.81 64.77 0)
			(effects
				(font
					(size 1.27 1.27)
					(thickness 0.15)
				)
				(justify left bottom)
				(hide yes)
			)
		)
		(property "Value" "GND"
			(at 375.92 66.04 0)
			(effects
				(font
					(size 1.27 1.27)
					(thickness 0.15)
				)
			)
		)
		(property "Footprint" ""
			(at 384.81 69.85 0)
			(effects
				(font
					(size 1.27 1.27)
					(thickness 0.15)
				)
				(justify left bottom)
				(hide yes)
			)
		)
		(property "Datasheet" ""
			(at 384.81 74.93 0)
			(effects
				(font
					(size 1.27 1.27)
					(thickness 0.15)
				)
				(justify left bottom)
				(hide yes)
			)
		)
		(property "Description" ""
			(at 375.92 62.23 0)
			(effects
				(font
					(size 1.27 1.27)
				)
				(hide yes)
			)
		)
		(property "Author" "Antmicro"
			(at 384.81 69.85 0)
			(effects
				(font
					(size 1.27 1.27)
					(thickness 0.15)
				)
				(justify left bottom)
				(hide yes)
			)
		)
		(property "License" "Apache-2.0"
			(at 384.81 72.39 0)
			(effects
				(font
					(size 1.27 1.27)
					(thickness 0.15)
				)
				(justify left bottom)
				(hide yes)
			)
		)
		(pin "1"
		)
		(instances
			(project "jetson-agx-thor-baseboard"
				(path ""
					(reference "#PWR027")
					(unit 1)
				)
			)
		)
	)
	(symbol
		(lib_id "antmicropower:GND")
		(at 290.83 199.39 0)
		(unit 1)
		(exclude_from_sim no)
		(in_bom yes)
		(on_board yes)
		(dnp no)
		(property "Reference" "#PWR0119"
			(at 290.83 205.74 0)
			(effects
				(font
					(size 1.27 1.27)
				)
				(justify left bottom)
				(hide yes)
			)
		)
		(property "Value" "GND"
			(at 290.83 203.2 0)
			(effects
				(font
					(size 1.27 1.27)
					(thickness 0.15)
				)
			)
		)
		(property "Footprint" ""
			(at 299.72 207.01 0)
			(effects
				(font
					(size 1.27 1.27)
					(thickness 0.15)
				)
				(justify left bottom)
				(hide yes)
			)
		)
		(property "Datasheet" ""
			(at 299.72 212.09 0)
			(effects
				(font
					(size 1.27 1.27)
					(thickness 0.15)
				)
				(justify left bottom)
				(hide yes)
			)
		)
		(property "Description" ""
			(at 290.83 199.39 0)
			(effects
				(font
					(size 1.27 1.27)
				)
				(hide yes)
			)
		)
		(property "Author" "Antmicro"
			(at 299.72 207.01 0)
			(effects
				(font
					(size 1.27 1.27)
					(thickness 0.15)
				)
				(justify left bottom)
				(hide yes)
			)
		)
		(property "License" "Apache-2.0"
			(at 299.72 209.55 0)
			(effects
				(font
					(size 1.27 1.27)
					(thickness 0.15)
				)
				(justify left bottom)
				(hide yes)
			)
		)
		(pin "1"
		)
		(instances
			(project "jetson-agx-thor-baseboard"
				(path ""
					(reference "#PWR0119")
					(unit 1)
				)
			)
		)
	)
	(symbol
		(lib_id "antmicropower:+5V")
		(at 39.37 30.48 0)
		(unit 1)
		(exclude_from_sim no)
		(in_bom yes)
		(on_board yes)
		(dnp no)
		(property "Reference" "#PWR042"
			(at 39.37 34.29 0)
			(effects
				(font
					(size 1.27 1.27)
				)
				(justify left bottom)
				(hide yes)
			)
		)
		(property "Value" "+5V_AON"
			(at 39.37 26.162 0)
			(effects
				(font
					(size 1.27 1.27)
					(thickness 0.15)
				)
			)
		)
		(property "Footprint" ""
			(at 54.61 38.1 0)
			(effects
				(font
					(size 1.27 1.27)
					(thickness 0.15)
				)
				(justify left bottom)
				(hide yes)
			)
		)
		(property "Datasheet" ""
			(at 54.61 40.64 0)
			(effects
				(font
					(size 1.27 1.27)
					(thickness 0.15)
				)
				(justify left bottom)
				(hide yes)
			)
		)
		(property "Description" ""
			(at 39.37 30.48 0)
			(effects
				(font
					(size 1.27 1.27)
				)
				(hide yes)
			)
		)
		(property "Author" "Antmicro"
			(at 54.61 38.1 0)
			(effects
				(font
					(size 1.27 1.27)
					(thickness 0.15)
				)
				(justify left bottom)
				(hide yes)
			)
		)
		(property "License" "Apache-2.0"
			(at 54.61 40.64 0)
			(effects
				(font
					(size 1.27 1.27)
					(thickness 0.15)
				)
				(justify left bottom)
				(hide yes)
			)
		)
		(pin "1"
		)
		(instances
			(project "jetson-agx-thor-baseboard"
				(path ""
					(reference "#PWR042")
					(unit 1)
				)
			)
		)
	)
	(symbol
		(lib_id "antmicroResistors0402:R_470R_0402")
		(at 54.61 86.36 270)
		(mirror x)
		(unit 1)
		(exclude_from_sim no)
		(in_bom yes)
		(on_board yes)
		(dnp no)
		(property "Reference" "R407"
			(at 53.34 82.55 90)
			(effects
				(font
					(size 1.27 1.27)
				)
				(justify right)
			)
		)
		(property "Value" "R_470R_0402"
			(at 41.91 66.04 0)
			(effects
				(font
					(size 1.27 1.27)
					(thickness 0.15)
				)
				(justify left bottom)
				(hide yes)
			)
		)
		(property "Footprint" "antmicro-footprints:R_0402_1005Metric"
			(at 39.37 66.04 0)
			(effects
				(font
					(size 1.27 1.27)
					(thickness 0.15)
				)
				(justify left bottom)
				(hide yes)
			)
		)
		(property "Datasheet" "https://www.bourns.com/docs/product-datasheets/cr.pdf"
			(at 36.83 66.04 0)
			(effects
				(font
					(size 1.27 1.27)
					(thickness 0.15)
				)
				(justify left bottom)
				(hide yes)
			)
		)
		(property "Description" "SMD Chip Resistor, 470 ohm, ± 1%, 62.5 mW, 0402 [1005 Metric], Thick Film, General Purpose"
			(at 54.61 86.36 0)
			(effects
				(font
					(size 1.27 1.27)
				)
				(hide yes)
			)
		)
		(property "Manufacturer" "Bourns"
			(at 31.75 66.04 0)
			(effects
				(font
					(size 1.27 1.27)
					(thickness 0.15)
				)
				(justify left bottom)
				(hide yes)
			)
		)
		(property "MPN" "CR0402-FX-4700GLF"
			(at 34.29 66.04 0)
			(effects
				(font
					(size 1.27 1.27)
					(thickness 0.15)
				)
				(justify left bottom)
				(hide yes)
			)
		)
		(property "Val" "470R"
			(at 53.34 85.09 90)
			(effects
				(font
					(size 1.27 1.27)
					(thickness 0.15)
				)
				(justify right)
			)
		)
		(property "License" "Apache-2.0"
			(at 29.21 66.04 0)
			(effects
				(font
					(size 1.27 1.27)
					(thickness 0.15)
				)
				(justify left bottom)
				(hide yes)
			)
		)
		(property "Author" "Antmicro"
			(at 26.67 66.04 0)
			(effects
				(font
					(size 1.27 1.27)
					(thickness 0.15)
				)
				(justify left bottom)
				(hide yes)
			)
		)
		(property "Tolerance" "1%"
			(at 44.45 66.04 0)
			(effects
				(font
					(size 1.27 1.27)
				)
				(justify left bottom)
				(hide yes)
			)
		)
		(pin "1"
		)
		(pin "2"
		)
		(instances
			(project "jetson-agx-thor-baseboard"
				(path ""
					(reference "R407")
					(unit 1)
				)
			)
		)
	)
	(symbol
		(lib_id "antmicroTransistorsFETsMOSFETsSingle:DMG1012T-7")
		(at 369.57 223.52 0)
		(unit 1)
		(exclude_from_sim no)
		(in_bom yes)
		(on_board yes)
		(dnp no)
		(property "Reference" "Q11"
			(at 379.73 226.06 90)
			(effects
				(font
					(size 1.27 1.27)
					(thickness 0.15)
				)
				(justify left)
			)
		)
		(property "Value" "DMG1012T-7"
			(at 392.43 240.03 0)
			(effects
				(font
					(size 1.27 1.27)
					(thickness 0.15)
				)
				(justify left bottom)
				(hide yes)
			)
		)
		(property "Footprint" "antmicro-footprints:SOT-523"
			(at 392.43 234.95 0)
			(effects
				(font
					(size 1.27 1.27)
					(thickness 0.15)
				)
				(justify left bottom)
				(hide yes)
			)
		)
		(property "Datasheet" "https://www.diodes.com/assets/Datasheets/ds31783.pdf"
			(at 392.43 237.49 0)
			(effects
				(font
					(size 1.27 1.27)
					(thickness 0.15)
				)
				(justify left bottom)
				(hide yes)
			)
		)
		(property "Description" "Power MOSFET, N Channel, 20 V, 630 mA, 0.3 ohm, SOT-523, Surface Mount"
			(at 428.752 249.428 0)
			(effects
				(font
					(size 1.27 1.27)
				)
				(hide yes)
			)
		)
		(property "MPN" "DMG1012T-7"
			(at 382.27 226.06 90)
			(effects
				(font
					(size 1.27 1.27)
					(thickness 0.15)
				)
				(justify left)
			)
		)
		(property "Manufacturer" "Diodes Incorporated"
			(at 392.43 242.57 0)
			(effects
				(font
					(size 1.27 1.27)
					(thickness 0.15)
				)
				(justify left bottom)
				(hide yes)
			)
		)
		(property "Author" "Antmicro"
			(at 392.43 245.11 0)
			(effects
				(font
					(size 1.27 1.27)
					(thickness 0.15)
				)
				(justify left bottom)
				(hide yes)
			)
		)
		(property "License" "Apache-2.0"
			(at 392.43 247.65 0)
			(effects
				(font
					(size 1.27 1.27)
					(thickness 0.15)
				)
				(justify left bottom)
				(hide yes)
			)
		)
		(pin "1"
		)
		(pin "3"
		)
		(pin "2"
		)
		(instances
			(project "jetson-agx-thor-baseboard"
				(path ""
					(reference "Q11")
					(unit 1)
				)
			)
		)
	)
	(symbol
		(lib_id "antmicroResistors0402:R_0R_0402")
		(at 226.06 266.7 0)
		(unit 1)
		(exclude_from_sim no)
		(in_bom yes)
		(on_board yes)
		(dnp no)
		(property "Reference" "R298"
			(at 224.155 265.43 0)
			(effects
				(font
					(size 1.27 1.27)
					(thickness 0.15)
				)
			)
		)
		(property "Value" "R_0R_0402"
			(at 246.38 279.4 0)
			(effects
				(font
					(size 1.27 1.27)
					(thickness 0.15)
				)
				(justify left bottom)
				(hide yes)
			)
		)
		(property "Footprint" "antmicro-footprints:R_0402_1005Metric"
			(at 246.38 281.94 0)
			(effects
				(font
					(size 1.27 1.27)
					(thickness 0.15)
				)
				(justify left bottom)
				(hide yes)
			)
		)
		(property "Datasheet" "https://industrial.panasonic.com/cdbs/www-data/pdf/RDA0000/AOA0000C301.pdf"
			(at 246.38 284.48 0)
			(effects
				(font
					(size 1.27 1.27)
					(thickness 0.15)
				)
				(justify left bottom)
				(hide yes)
			)
		)
		(property "Description" "SMD Chip Resistor, Jumper, 0 ohm, 100 mW, 0402 [1005 Metric], Thick Film, General Purpose"
			(at 226.06 266.7 0)
			(effects
				(font
					(size 1.27 1.27)
				)
				(hide yes)
			)
		)
		(property "MPN" "ERJ2GE0R00X"
			(at 246.38 287.02 0)
			(effects
				(font
					(size 1.27 1.27)
					(thickness 0.15)
				)
				(justify left bottom)
				(hide yes)
			)
		)
		(property "Manufacturer" "Panasonic"
			(at 246.38 289.56 0)
			(effects
				(font
					(size 1.27 1.27)
					(thickness 0.15)
				)
				(justify left bottom)
				(hide yes)
			)
		)
		(property "License" "Apache-2.0"
			(at 246.38 292.1 0)
			(effects
				(font
					(size 1.27 1.27)
					(thickness 0.15)
				)
				(justify left bottom)
				(hide yes)
			)
		)
		(property "Author" "Antmicro"
			(at 246.38 294.64 0)
			(effects
				(font
					(size 1.27 1.27)
					(thickness 0.15)
				)
				(justify left bottom)
				(hide yes)
			)
		)
		(property "Val" "0R"
			(at 232.41 265.43 0)
			(effects
				(font
					(size 1.27 1.27)
					(thickness 0.15)
				)
			)
		)
		(property "Tolerance" "~"
			(at 246.38 276.86 0)
			(effects
				(font
					(size 1.27 1.27)
				)
				(justify left bottom)
				(hide yes)
			)
		)
		(property "Current" "1A"
			(at 246.38 297.18 0)
			(effects
				(font
					(size 1.27 1.27)
					(thickness 0.15)
				)
				(justify left bottom)
				(hide yes)
			)
		)
		(pin "2"
		)
		(pin "1"
		)
		(instances
			(project "jetson-agx-thor-baseboard"
				(path ""
					(reference "R298")
					(unit 1)
				)
			)
		)
	)
	(symbol
		(lib_id "antmicropower:+3V3_AON")
		(at 213.36 209.55 0)
		(unit 1)
		(exclude_from_sim no)
		(in_bom yes)
		(on_board yes)
		(dnp no)
		(property "Reference" "#PWR0341"
			(at 213.36 213.36 0)
			(effects
				(font
					(size 1.27 1.27)
				)
				(hide yes)
			)
		)
		(property "Value" "+1V8"
			(at 213.36 205.74 0)
			(effects
				(font
					(size 1.27 1.27)
				)
			)
		)
		(property "Footprint" ""
			(at 213.36 209.55 0)
			(effects
				(font
					(size 1.27 1.27)
				)
				(hide yes)
			)
		)
		(property "Datasheet" ""
			(at 213.36 209.55 0)
			(effects
				(font
					(size 1.27 1.27)
				)
				(hide yes)
			)
		)
		(property "Description" ""
			(at 213.36 209.55 0)
			(effects
				(font
					(size 1.27 1.27)
				)
				(hide yes)
			)
		)
		(pin "1"
		)
		(instances
			(project "jetson-agx-thor-baseboard"
				(path ""
					(reference "#PWR0341")
					(unit 1)
				)
			)
		)
	)
	(symbol
		(lib_id "antmicroResistors0402:R_0R_0402")
		(at 226.06 217.17 0)
		(unit 1)
		(exclude_from_sim no)
		(in_bom yes)
		(on_board yes)
		(dnp no)
		(property "Reference" "R297"
			(at 224.155 215.9 0)
			(effects
				(font
					(size 1.27 1.27)
					(thickness 0.15)
				)
			)
		)
		(property "Value" "R_0R_0402"
			(at 246.38 229.87 0)
			(effects
				(font
					(size 1.27 1.27)
					(thickness 0.15)
				)
				(justify left bottom)
				(hide yes)
			)
		)
		(property "Footprint" "antmicro-footprints:R_0402_1005Metric"
			(at 246.38 232.41 0)
			(effects
				(font
					(size 1.27 1.27)
					(thickness 0.15)
				)
				(justify left bottom)
				(hide yes)
			)
		)
		(property "Datasheet" "https://industrial.panasonic.com/cdbs/www-data/pdf/RDA0000/AOA0000C301.pdf"
			(at 246.38 234.95 0)
			(effects
				(font
					(size 1.27 1.27)
					(thickness 0.15)
				)
				(justify left bottom)
				(hide yes)
			)
		)
		(property "Description" "SMD Chip Resistor, Jumper, 0 ohm, 100 mW, 0402 [1005 Metric], Thick Film, General Purpose"
			(at 226.06 217.17 0)
			(effects
				(font
					(size 1.27 1.27)
				)
				(hide yes)
			)
		)
		(property "MPN" "ERJ2GE0R00X"
			(at 246.38 237.49 0)
			(effects
				(font
					(size 1.27 1.27)
					(thickness 0.15)
				)
				(justify left bottom)
				(hide yes)
			)
		)
		(property "Manufacturer" "Panasonic"
			(at 246.38 240.03 0)
			(effects
				(font
					(size 1.27 1.27)
					(thickness 0.15)
				)
				(justify left bottom)
				(hide yes)
			)
		)
		(property "License" "Apache-2.0"
			(at 246.38 242.57 0)
			(effects
				(font
					(size 1.27 1.27)
					(thickness 0.15)
				)
				(justify left bottom)
				(hide yes)
			)
		)
		(property "Author" "Antmicro"
			(at 246.38 245.11 0)
			(effects
				(font
					(size 1.27 1.27)
					(thickness 0.15)
				)
				(justify left bottom)
				(hide yes)
			)
		)
		(property "Val" "0R"
			(at 232.41 215.9 0)
			(effects
				(font
					(size 1.27 1.27)
					(thickness 0.15)
				)
			)
		)
		(property "Tolerance" "~"
			(at 246.38 227.33 0)
			(effects
				(font
					(size 1.27 1.27)
				)
				(justify left bottom)
				(hide yes)
			)
		)
		(property "Current" "1A"
			(at 246.38 247.65 0)
			(effects
				(font
					(size 1.27 1.27)
					(thickness 0.15)
				)
				(justify left bottom)
				(hide yes)
			)
		)
		(pin "2"
		)
		(pin "1"
		)
		(instances
			(project "jetson-agx-thor-baseboard"
				(path ""
					(reference "R297")
					(unit 1)
				)
			)
		)
	)
	(symbol
		(lib_id "antmicroTransistorsFETsMOSFETsSingle:DMG1012T-7")
		(at 317.5 177.8 0)
		(unit 1)
		(exclude_from_sim no)
		(in_bom yes)
		(on_board yes)
		(dnp no)
		(property "Reference" "Q37"
			(at 327.66 180.086 90)
			(effects
				(font
					(size 1.27 1.27)
					(thickness 0.15)
				)
				(justify left)
			)
		)
		(property "Value" "DMG1012T-7"
			(at 340.36 194.31 0)
			(effects
				(font
					(size 1.27 1.27)
					(thickness 0.15)
				)
				(justify left bottom)
				(hide yes)
			)
		)
		(property "Footprint" "antmicro-footprints:SOT-523"
			(at 340.36 189.23 0)
			(effects
				(font
					(size 1.27 1.27)
					(thickness 0.15)
				)
				(justify left bottom)
				(hide yes)
			)
		)
		(property "Datasheet" "https://www.diodes.com/assets/Datasheets/ds31783.pdf"
			(at 340.36 191.77 0)
			(effects
				(font
					(size 1.27 1.27)
					(thickness 0.15)
				)
				(justify left bottom)
				(hide yes)
			)
		)
		(property "Description" "Power MOSFET, N Channel, 20 V, 630 mA, 0.3 ohm, SOT-523, Surface Mount"
			(at 376.682 203.708 0)
			(effects
				(font
					(size 1.27 1.27)
				)
				(hide yes)
			)
		)
		(property "MPN" "DMG1012T-7"
			(at 330.2 180.086 90)
			(effects
				(font
					(size 1.27 1.27)
					(thickness 0.15)
				)
				(justify left)
			)
		)
		(property "Manufacturer" "Diodes Incorporated"
			(at 340.36 196.85 0)
			(effects
				(font
					(size 1.27 1.27)
					(thickness 0.15)
				)
				(justify left bottom)
				(hide yes)
			)
		)
		(property "Author" "Antmicro"
			(at 340.36 199.39 0)
			(effects
				(font
					(size 1.27 1.27)
					(thickness 0.15)
				)
				(justify left bottom)
				(hide yes)
			)
		)
		(property "License" "Apache-2.0"
			(at 340.36 201.93 0)
			(effects
				(font
					(size 1.27 1.27)
					(thickness 0.15)
				)
				(justify left bottom)
				(hide yes)
			)
		)
		(pin "1"
		)
		(pin "3"
		)
		(pin "2"
		)
		(instances
			(project "jetson-agx-thor-baseboard"
				(path ""
					(reference "Q37")
					(unit 1)
				)
			)
		)
	)
)
